(kicad_sch
	(version 20250114)
	(generator "eeschema")
	(generator_version "9.0")
	(paper "A3")
	(title_block
		(title "M.2 to PCIe adapter")
		(rev "1.2.2")
		(comment 1 "www.antmicro.com")
		(comment 2 "Antmicro Ltd.")
	)
	(text "Auxilary connector"
		(exclude_from_sim no)
		(at 213.36 185.42 0)
		(effects
			(font
				(size 2.9972 2.9972)
				(thickness 0.5994)
				(bold yes)
			)
			(justify left bottom)
		)
	)
	(text "M.2 (key M)"
		(exclude_from_sim no)
		(at 212.09 24.13 0)
		(effects
			(font
				(size 2.9972 2.9972)
				(thickness 0.5994)
				(bold yes)
			)
			(justify left bottom)
		)
	)
	(text "PCB edge connector"
		(exclude_from_sim no)
		(at 288.29 38.1 0)
		(effects
			(font
				(size 1.27 1.27)
			)
			(justify left bottom)
		)
	)
	(text "PCIe x4"
		(exclude_from_sim no)
		(at 16.51 24.13 0)
		(effects
			(font
				(size 2.9972 2.9972)
				(thickness 0.5994)
				(bold yes)
			)
			(justify left bottom)
		)
	)
	(text "Place close to the PCIe"
		(exclude_from_sim no)
		(at 146.05 223.52 0)
		(effects
			(font
				(size 1.27 1.27)
			)
			(justify left bottom)
		)
	)
	(text "Power supply filtering"
		(exclude_from_sim no)
		(at 24.13 185.42 0)
		(effects
			(font
				(size 2.9972 2.9972)
				(thickness 0.5994)
				(bold yes)
			)
			(justify left bottom)
		)
	)
	(junction
		(at 125.73 105.41)
		(diameter 0)
		(color 0 0 0 0)
	)
	(junction
		(at 85.09 107.95)
		(diameter 0)
		(color 0 0 0 0)
	)
	(junction
		(at 85.09 135.89)
		(diameter 0)
		(color 0 0 0 0)
	)
	(junction
		(at 125.73 123.19)
		(diameter 0)
		(color 0 0 0 0)
	)
	(junction
		(at 125.73 85.09)
		(diameter 0)
		(color 0 0 0 0)
	)
	(junction
		(at 83.82 203.2)
		(diameter 0)
		(color 0 0 0 0)
	)
	(junction
		(at 242.57 208.28)
		(diameter 0)
		(color 0 0 0 0)
	)
	(junction
		(at 125.73 92.71)
		(diameter 0)
		(color 0 0 0 0)
	)
	(junction
		(at 125.73 133.35)
		(diameter 0)
		(color 0 0 0 0)
	)
	(junction
		(at 85.09 54.61)
		(diameter 0)
		(color 0 0 0 0)
	)
	(junction
		(at 85.09 118.11)
		(diameter 0)
		(color 0 0 0 0)
	)
	(junction
		(at 85.09 100.33)
		(diameter 0)
		(color 0 0 0 0)
	)
	(junction
		(at 147.32 203.2)
		(diameter 0)
		(color 0 0 0 0)
	)
	(junction
		(at 125.73 115.57)
		(diameter 0)
		(color 0 0 0 0)
	)
	(junction
		(at 85.09 87.63)
		(diameter 0)
		(color 0 0 0 0)
	)
	(junction
		(at 73.66 203.2)
		(diameter 0)
		(color 0 0 0 0)
	)
	(junction
		(at 85.09 110.49)
		(diameter 0)
		(color 0 0 0 0)
	)
	(junction
		(at 85.09 69.85)
		(diameter 0)
		(color 0 0 0 0)
	)
	(junction
		(at 101.6 203.2)
		(diameter 0)
		(color 0 0 0 0)
	)
	(junction
		(at 85.09 120.65)
		(diameter 0)
		(color 0 0 0 0)
	)
	(junction
		(at 157.48 203.2)
		(diameter 0)
		(color 0 0 0 0)
	)
	(junction
		(at 85.09 128.27)
		(diameter 0)
		(color 0 0 0 0)
	)
	(junction
		(at 125.73 125.73)
		(diameter 0)
		(color 0 0 0 0)
	)
	(junction
		(at 125.73 113.03)
		(diameter 0)
		(color 0 0 0 0)
	)
	(junction
		(at 39.37 203.2)
		(diameter 0)
		(color 0 0 0 0)
	)
	(junction
		(at 111.76 203.2)
		(diameter 0)
		(color 0 0 0 0)
	)
	(junction
		(at 125.73 100.33)
		(diameter 0)
		(color 0 0 0 0)
	)
	(junction
		(at 125.73 57.15)
		(diameter 0)
		(color 0 0 0 0)
	)
	(junction
		(at 85.09 57.15)
		(diameter 0)
		(color 0 0 0 0)
	)
	(junction
		(at 85.09 95.25)
		(diameter 0)
		(color 0 0 0 0)
	)
	(no_connect
		(at 121.92 72.39)
	)
	(no_connect
		(at 88.9 74.93)
	)
	(no_connect
		(at 121.92 69.85)
	)
	(no_connect
		(at 317.5 49.53)
	)
	(no_connect
		(at 121.92 67.31)
	)
	(no_connect
		(at 317.5 52.07)
	)
	(no_connect
		(at 121.92 64.77)
	)
	(no_connect
		(at 88.9 64.77)
	)
	(no_connect
		(at 88.9 67.31)
	)
	(no_connect
		(at 121.92 135.89)
	)
	(no_connect
		(at 88.9 97.79)
	)
	(no_connect
		(at 279.4 110.49)
	)
	(no_connect
		(at 88.9 130.81)
	)
	(no_connect
		(at 88.9 133.35)
	)
	(no_connect
		(at 317.5 62.23)
	)
	(no_connect
		(at 88.9 85.09)
	)
	(no_connect
		(at 121.92 54.61)
	)
	(no_connect
		(at 121.92 102.87)
	)
	(wire
		(pts
			(xy 85.09 120.65) (xy 85.09 118.11)
		)
		(stroke
			(width 0)
			(type default)
		)
	)
	(wire
		(pts
			(xy 125.73 115.57) (xy 125.73 113.03)
		)
		(stroke
			(width 0)
			(type default)
		)
	)
	(wire
		(pts
			(xy 83.82 203.2) (xy 73.66 203.2)
		)
		(stroke
			(width 0)
			(type default)
		)
	)
	(wire
		(pts
			(xy 121.92 113.03) (xy 125.73 113.03)
		)
		(stroke
			(width 0)
			(type default)
		)
	)
	(wire
		(pts
			(xy 88.9 72.39) (xy 71.12 72.39)
		)
		(stroke
			(width 0)
			(type default)
		)
	)
	(wire
		(pts
			(xy 88.9 110.49) (xy 85.09 110.49)
		)
		(stroke
			(width 0)
			(type default)
		)
	)
	(wire
		(pts
			(xy 85.09 57.15) (xy 85.09 54.61)
		)
		(stroke
			(width 0)
			(type default)
		)
	)
	(wire
		(pts
			(xy 111.76 203.2) (xy 125.73 203.2)
		)
		(stroke
			(width 0)
			(type default)
		)
	)
	(wire
		(pts
			(xy 279.4 106.68) (xy 261.62 106.68)
		)
		(stroke
			(width 0)
			(type default)
		)
	)
	(wire
		(pts
			(xy 88.9 62.23) (xy 85.09 62.23)
		)
		(stroke
			(width 0)
			(type default)
		)
	)
	(wire
		(pts
			(xy 279.4 87.63) (xy 261.62 87.63)
		)
		(stroke
			(width 0)
			(type default)
		)
	)
	(wire
		(pts
			(xy 121.92 118.11) (xy 139.7 118.11)
		)
		(stroke
			(width 0)
			(type default)
		)
	)
	(wire
		(pts
			(xy 85.09 142.24) (xy 85.09 135.89)
		)
		(stroke
			(width 0)
			(type default)
		)
	)
	(wire
		(pts
			(xy 85.09 87.63) (xy 85.09 69.85)
		)
		(stroke
			(width 0)
			(type default)
		)
	)
	(wire
		(pts
			(xy 73.66 208.28) (xy 73.66 203.2)
		)
		(stroke
			(width 0)
			(type default)
		)
	)
	(wire
		(pts
			(xy 125.73 123.19) (xy 125.73 125.73)
		)
		(stroke
			(width 0)
			(type default)
		)
	)
	(wire
		(pts
			(xy 168.91 203.2) (xy 168.91 208.28)
		)
		(stroke
			(width 0)
			(type default)
		)
	)
	(wire
		(pts
			(xy 121.92 123.19) (xy 125.73 123.19)
		)
		(stroke
			(width 0)
			(type default)
		)
	)
	(wire
		(pts
			(xy 125.73 105.41) (xy 125.73 113.03)
		)
		(stroke
			(width 0)
			(type default)
		)
	)
	(wire
		(pts
			(xy 279.4 104.14) (xy 261.62 104.14)
		)
		(stroke
			(width 0)
			(type default)
		)
	)
	(wire
		(pts
			(xy 125.73 57.15) (xy 125.73 46.99)
		)
		(stroke
			(width 0)
			(type default)
		)
	)
	(wire
		(pts
			(xy 95.25 203.2) (xy 101.6 203.2)
		)
		(stroke
			(width 0)
			(type default)
		)
	)
	(wire
		(pts
			(xy 279.4 97.79) (xy 261.62 97.79)
		)
		(stroke
			(width 0)
			(type default)
		)
	)
	(wire
		(pts
			(xy 71.12 77.47) (xy 88.9 77.47)
		)
		(stroke
			(width 0)
			(type default)
		)
	)
	(wire
		(pts
			(xy 88.9 57.15) (xy 85.09 57.15)
		)
		(stroke
			(width 0)
			(type default)
		)
	)
	(wire
		(pts
			(xy 68.58 80.01) (xy 88.9 80.01)
		)
		(stroke
			(width 0)
			(type default)
		)
	)
	(wire
		(pts
			(xy 121.92 95.25) (xy 139.7 95.25)
		)
		(stroke
			(width 0)
			(type default)
		)
	)
	(wire
		(pts
			(xy 125.73 142.24) (xy 125.73 133.35)
		)
		(stroke
			(width 0)
			(type default)
		)
	)
	(wire
		(pts
			(xy 88.9 59.69) (xy 85.09 59.69)
		)
		(stroke
			(width 0)
			(type default)
		)
	)
	(wire
		(pts
			(xy 320.04 114.3) (xy 320.04 110.49)
		)
		(stroke
			(width 0)
			(type default)
		)
	)
	(wire
		(pts
			(xy 279.4 53.34) (xy 261.62 53.34)
		)
		(stroke
			(width 0)
			(type default)
		)
	)
	(wire
		(pts
			(xy 121.92 120.65) (xy 139.7 120.65)
		)
		(stroke
			(width 0)
			(type default)
		)
	)
	(wire
		(pts
			(xy 125.73 105.41) (xy 125.73 100.33)
		)
		(stroke
			(width 0)
			(type default)
		)
	)
	(wire
		(pts
			(xy 85.09 59.69) (xy 85.09 57.15)
		)
		(stroke
			(width 0)
			(type default)
		)
	)
	(wire
		(pts
			(xy 279.4 68.58) (xy 261.62 68.58)
		)
		(stroke
			(width 0)
			(type default)
		)
	)
	(wire
		(pts
			(xy 88.9 135.89) (xy 85.09 135.89)
		)
		(stroke
			(width 0)
			(type default)
		)
	)
	(wire
		(pts
			(xy 279.4 93.98) (xy 261.62 93.98)
		)
		(stroke
			(width 0)
			(type default)
		)
	)
	(wire
		(pts
			(xy 121.92 77.47) (xy 139.7 77.47)
		)
		(stroke
			(width 0)
			(type default)
		)
	)
	(wire
		(pts
			(xy 279.4 59.69) (xy 261.62 59.69)
		)
		(stroke
			(width 0)
			(type default)
		)
	)
	(wire
		(pts
			(xy 121.92 87.63) (xy 139.7 87.63)
		)
		(stroke
			(width 0)
			(type default)
		)
	)
	(wire
		(pts
			(xy 157.48 203.2) (xy 168.91 203.2)
		)
		(stroke
			(width 0)
			(type default)
		)
	)
	(wire
		(pts
			(xy 88.9 120.65) (xy 85.09 120.65)
		)
		(stroke
			(width 0)
			(type default)
		)
	)
	(wire
		(pts
			(xy 242.57 205.74) (xy 242.57 208.28)
		)
		(stroke
			(width 0)
			(type default)
		)
	)
	(wire
		(pts
			(xy 279.4 55.88) (xy 261.62 55.88)
		)
		(stroke
			(width 0)
			(type default)
		)
	)
	(wire
		(pts
			(xy 279.4 91.44) (xy 261.62 91.44)
		)
		(stroke
			(width 0)
			(type default)
		)
	)
	(wire
		(pts
			(xy 121.92 62.23) (xy 125.73 62.23)
		)
		(stroke
			(width 0)
			(type default)
		)
	)
	(wire
		(pts
			(xy 121.92 115.57) (xy 125.73 115.57)
		)
		(stroke
			(width 0)
			(type default)
		)
	)
	(wire
		(pts
			(xy 121.92 130.81) (xy 139.7 130.81)
		)
		(stroke
			(width 0)
			(type default)
		)
	)
	(wire
		(pts
			(xy 39.37 203.2) (xy 39.37 208.28)
		)
		(stroke
			(width 0)
			(type default)
		)
	)
	(wire
		(pts
			(xy 88.9 69.85) (xy 85.09 69.85)
		)
		(stroke
			(width 0)
			(type default)
		)
	)
	(wire
		(pts
			(xy 88.9 87.63) (xy 85.09 87.63)
		)
		(stroke
			(width 0)
			(type default)
		)
	)
	(wire
		(pts
			(xy 121.92 90.17) (xy 139.7 90.17)
		)
		(stroke
			(width 0)
			(type default)
		)
	)
	(wire
		(pts
			(xy 85.09 110.49) (xy 85.09 107.95)
		)
		(stroke
			(width 0)
			(type default)
		)
	)
	(wire
		(pts
			(xy 85.09 100.33) (xy 85.09 95.25)
		)
		(stroke
			(width 0)
			(type default)
		)
	)
	(wire
		(pts
			(xy 88.9 100.33) (xy 85.09 100.33)
		)
		(stroke
			(width 0)
			(type default)
		)
	)
	(wire
		(pts
			(xy 279.4 85.09) (xy 261.62 85.09)
		)
		(stroke
			(width 0)
			(type default)
		)
	)
	(wire
		(pts
			(xy 121.92 80.01) (xy 140.97 80.01)
		)
		(stroke
			(width 0)
			(type default)
		)
	)
	(wire
		(pts
			(xy 121.92 133.35) (xy 125.73 133.35)
		)
		(stroke
			(width 0)
			(type default)
		)
	)
	(wire
		(pts
			(xy 88.9 90.17) (xy 71.12 90.17)
		)
		(stroke
			(width 0)
			(type default)
		)
	)
	(wire
		(pts
			(xy 88.9 107.95) (xy 85.09 107.95)
		)
		(stroke
			(width 0)
			(type default)
		)
	)
	(wire
		(pts
			(xy 125.73 59.69) (xy 125.73 57.15)
		)
		(stroke
			(width 0)
			(type default)
		)
	)
	(wire
		(pts
			(xy 125.73 85.09) (xy 125.73 62.23)
		)
		(stroke
			(width 0)
			(type default)
		)
	)
	(wire
		(pts
			(xy 121.92 105.41) (xy 125.73 105.41)
		)
		(stroke
			(width 0)
			(type default)
		)
	)
	(wire
		(pts
			(xy 279.4 100.33) (xy 261.62 100.33)
		)
		(stroke
			(width 0)
			(type default)
		)
	)
	(wire
		(pts
			(xy 73.66 203.2) (xy 64.77 203.2)
		)
		(stroke
			(width 0)
			(type default)
		)
	)
	(wire
		(pts
			(xy 111.76 208.28) (xy 111.76 203.2)
		)
		(stroke
			(width 0)
			(type default)
		)
	)
	(wire
		(pts
			(xy 121.92 92.71) (xy 125.73 92.71)
		)
		(stroke
			(width 0)
			(type default)
		)
	)
	(wire
		(pts
			(xy 85.09 54.61) (xy 85.09 46.99)
		)
		(stroke
			(width 0)
			(type default)
		)
	)
	(wire
		(pts
			(xy 88.9 105.41) (xy 71.12 105.41)
		)
		(stroke
			(width 0)
			(type default)
		)
	)
	(wire
		(pts
			(xy 88.9 115.57) (xy 71.12 115.57)
		)
		(stroke
			(width 0)
			(type default)
		)
	)
	(wire
		(pts
			(xy 121.92 128.27) (xy 139.7 128.27)
		)
		(stroke
			(width 0)
			(type default)
		)
	)
	(wire
		(pts
			(xy 238.76 210.82) (xy 243.84 210.82)
		)
		(stroke
			(width 0)
			(type default)
		)
	)
	(wire
		(pts
			(xy 88.9 113.03) (xy 71.12 113.03)
		)
		(stroke
			(width 0)
			(type default)
		)
	)
	(wire
		(pts
			(xy 121.92 110.49) (xy 139.7 110.49)
		)
		(stroke
			(width 0)
			(type default)
		)
	)
	(wire
		(pts
			(xy 121.92 57.15) (xy 125.73 57.15)
		)
		(stroke
			(width 0)
			(type default)
		)
	)
	(wire
		(pts
			(xy 232.41 228.6) (xy 234.95 228.6)
		)
		(stroke
			(width 0)
			(type default)
		)
	)
	(wire
		(pts
			(xy 101.6 203.2) (xy 111.76 203.2)
		)
		(stroke
			(width 0)
			(type default)
		)
	)
	(wire
		(pts
			(xy 88.9 102.87) (xy 71.12 102.87)
		)
		(stroke
			(width 0)
			(type default)
		)
	)
	(polyline
		(pts
			(xy 203.2 12.7) (xy 203.2 284.48)
		)
		(stroke
			(width 0)
			(type default)
		)
	)
	(wire
		(pts
			(xy 121.92 107.95) (xy 139.7 107.95)
		)
		(stroke
			(width 0)
			(type default)
		)
	)
	(wire
		(pts
			(xy 121.92 74.93) (xy 139.7 74.93)
		)
		(stroke
			(width 0)
			(type default)
		)
	)
	(wire
		(pts
			(xy 121.92 100.33) (xy 125.73 100.33)
		)
		(stroke
			(width 0)
			(type default)
		)
	)
	(wire
		(pts
			(xy 121.92 85.09) (xy 125.73 85.09)
		)
		(stroke
			(width 0)
			(type default)
		)
	)
	(wire
		(pts
			(xy 88.9 125.73) (xy 71.12 125.73)
		)
		(stroke
			(width 0)
			(type default)
		)
	)
	(wire
		(pts
			(xy 85.09 95.25) (xy 85.09 87.63)
		)
		(stroke
			(width 0)
			(type default)
		)
	)
	(wire
		(pts
			(xy 317.5 59.69) (xy 335.28 59.69)
		)
		(stroke
			(width 0)
			(type default)
		)
	)
	(wire
		(pts
			(xy 279.4 49.53) (xy 261.62 49.53)
		)
		(stroke
			(width 0)
			(type default)
		)
	)
	(wire
		(pts
			(xy 242.57 205.74) (xy 243.84 205.74)
		)
		(stroke
			(width 0)
			(type default)
		)
	)
	(wire
		(pts
			(xy 125.73 85.09) (xy 125.73 92.71)
		)
		(stroke
			(width 0)
			(type default)
		)
	)
	(wire
		(pts
			(xy 317.5 54.61) (xy 335.28 54.61)
		)
		(stroke
			(width 0)
			(type default)
		)
	)
	(wire
		(pts
			(xy 85.09 128.27) (xy 85.09 120.65)
		)
		(stroke
			(width 0)
			(type default)
		)
	)
	(wire
		(pts
			(xy 337.82 62.23) (xy 337.82 57.15)
		)
		(stroke
			(width 0)
			(type default)
		)
	)
	(wire
		(pts
			(xy 146.05 80.01) (xy 156.21 80.01)
		)
		(stroke
			(width 0)
			(type default)
		)
	)
	(wire
		(pts
			(xy 157.48 203.2) (xy 157.48 208.28)
		)
		(stroke
			(width 0)
			(type default)
		)
	)
	(wire
		(pts
			(xy 279.4 78.74) (xy 261.62 78.74)
		)
		(stroke
			(width 0)
			(type default)
		)
	)
	(wire
		(pts
			(xy 327.66 57.15) (xy 337.82 57.15)
		)
		(stroke
			(width 0)
			(type default)
		)
	)
	(wire
		(pts
			(xy 279.4 66.04) (xy 261.62 66.04)
		)
		(stroke
			(width 0)
			(type default)
		)
	)
	(polyline
		(pts
			(xy 12.7 171.45) (xy 408.94 171.45)
		)
		(stroke
			(width 0)
			(type default)
		)
	)
	(wire
		(pts
			(xy 242.57 208.28) (xy 243.84 208.28)
		)
		(stroke
			(width 0)
			(type default)
		)
	)
	(wire
		(pts
			(xy 85.09 107.95) (xy 85.09 100.33)
		)
		(stroke
			(width 0)
			(type default)
		)
	)
	(wire
		(pts
			(xy 125.73 100.33) (xy 125.73 92.71)
		)
		(stroke
			(width 0)
			(type default)
		)
	)
	(wire
		(pts
			(xy 125.73 123.19) (xy 125.73 115.57)
		)
		(stroke
			(width 0)
			(type default)
		)
	)
	(wire
		(pts
			(xy 88.9 128.27) (xy 85.09 128.27)
		)
		(stroke
			(width 0)
			(type default)
		)
	)
	(wire
		(pts
			(xy 85.09 135.89) (xy 85.09 128.27)
		)
		(stroke
			(width 0)
			(type default)
		)
	)
	(wire
		(pts
			(xy 85.09 69.85) (xy 85.09 62.23)
		)
		(stroke
			(width 0)
			(type default)
		)
	)
	(wire
		(pts
			(xy 101.6 203.2) (xy 101.6 208.28)
		)
		(stroke
			(width 0)
			(type default)
		)
	)
	(wire
		(pts
			(xy 88.9 92.71) (xy 71.12 92.71)
		)
		(stroke
			(width 0)
			(type default)
		)
	)
	(wire
		(pts
			(xy 125.73 133.35) (xy 125.73 125.73)
		)
		(stroke
			(width 0)
			(type default)
		)
	)
	(wire
		(pts
			(xy 147.32 208.28) (xy 147.32 203.2)
		)
		(stroke
			(width 0)
			(type default)
		)
	)
	(wire
		(pts
			(xy 83.82 208.28) (xy 83.82 203.2)
		)
		(stroke
			(width 0)
			(type default)
		)
	)
	(wire
		(pts
			(xy 90.17 203.2) (xy 83.82 203.2)
		)
		(stroke
			(width 0)
			(type default)
		)
	)
	(wire
		(pts
			(xy 85.09 118.11) (xy 85.09 110.49)
		)
		(stroke
			(width 0)
			(type default)
		)
	)
	(wire
		(pts
			(xy 279.4 81.28) (xy 261.62 81.28)
		)
		(stroke
			(width 0)
			(type default)
		)
	)
	(wire
		(pts
			(xy 243.84 203.2) (xy 238.76 203.2)
		)
		(stroke
			(width 0)
			(type default)
		)
	)
	(wire
		(pts
			(xy 279.4 74.93) (xy 261.62 74.93)
		)
		(stroke
			(width 0)
			(type default)
		)
	)
	(wire
		(pts
			(xy 121.92 59.69) (xy 125.73 59.69)
		)
		(stroke
			(width 0)
			(type default)
		)
	)
	(wire
		(pts
			(xy 279.4 62.23) (xy 261.62 62.23)
		)
		(stroke
			(width 0)
			(type default)
		)
	)
	(wire
		(pts
			(xy 317.5 57.15) (xy 322.58 57.15)
		)
		(stroke
			(width 0)
			(type default)
		)
	)
	(wire
		(pts
			(xy 121.92 97.79) (xy 139.7 97.79)
		)
		(stroke
			(width 0)
			(type default)
		)
	)
	(wire
		(pts
			(xy 50.8 208.28) (xy 50.8 203.2)
		)
		(stroke
			(width 0)
			(type default)
		)
	)
	(wire
		(pts
			(xy 50.8 203.2) (xy 39.37 203.2)
		)
		(stroke
			(width 0)
			(type default)
		)
	)
	(wire
		(pts
			(xy 39.37 203.2) (xy 39.37 201.93)
		)
		(stroke
			(width 0)
			(type default)
		)
	)
	(wire
		(pts
			(xy 63.5 80.01) (xy 53.34 80.01)
		)
		(stroke
			(width 0)
			(type default)
		)
	)
	(wire
		(pts
			(xy 279.4 72.39) (xy 261.62 72.39)
		)
		(stroke
			(width 0)
			(type default)
		)
	)
	(wire
		(pts
			(xy 88.9 118.11) (xy 85.09 118.11)
		)
		(stroke
			(width 0)
			(type default)
		)
	)
	(wire
		(pts
			(xy 232.41 237.49) (xy 234.95 237.49)
		)
		(stroke
			(width 0)
			(type default)
		)
	)
	(wire
		(pts
			(xy 147.32 203.2) (xy 138.43 203.2)
		)
		(stroke
			(width 0)
			(type default)
		)
	)
	(wire
		(pts
			(xy 147.32 203.2) (xy 157.48 203.2)
		)
		(stroke
			(width 0)
			(type default)
		)
	)
	(wire
		(pts
			(xy 121.92 125.73) (xy 125.73 125.73)
		)
		(stroke
			(width 0)
			(type default)
		)
	)
	(wire
		(pts
			(xy 88.9 95.25) (xy 85.09 95.25)
		)
		(stroke
			(width 0)
			(type default)
		)
	)
	(wire
		(pts
			(xy 317.5 110.49) (xy 320.04 110.49)
		)
		(stroke
			(width 0)
			(type default)
		)
	)
	(wire
		(pts
			(xy 88.9 123.19) (xy 71.12 123.19)
		)
		(stroke
			(width 0)
			(type default)
		)
	)
	(wire
		(pts
			(xy 242.57 214.63) (xy 242.57 208.28)
		)
		(stroke
			(width 0)
			(type default)
		)
	)
	(wire
		(pts
			(xy 88.9 54.61) (xy 85.09 54.61)
		)
		(stroke
			(width 0)
			(type default)
		)
	)
	(label "Data_3_IN_N"
		(at 139.7 130.81 180)
		(effects
			(font
				(size 1.27 1.27)
			)
			(justify right bottom)
		)
	)
	(label "Data_2_IN_N"
		(at 139.7 120.65 180)
		(effects
			(font
				(size 1.27 1.27)
			)
			(justify right bottom)
		)
	)
	(label "Data_2_OUT_P"
		(at 71.12 113.03 0)
		(effects
			(font
				(size 1.27 1.27)
			)
			(justify left bottom)
		)
	)
	(label "Data_0_IN_P"
		(at 261.62 91.44 0)
		(effects
			(font
				(size 1.27 1.27)
			)
			(justify left bottom)
		)
	)
	(label "Data_0_IN_P"
		(at 139.7 95.25 180)
		(effects
			(font
				(size 1.27 1.27)
			)
			(justify right bottom)
		)
	)
	(label "Data_1_OUT_P"
		(at 261.62 85.09 0)
		(effects
			(font
				(size 1.27 1.27)
			)
			(justify left bottom)
		)
	)
	(label "Data_1_OUT_N"
		(at 71.12 105.41 0)
		(effects
			(font
				(size 1.27 1.27)
			)
			(justify left bottom)
		)
	)
	(label "Data_1_IN_N"
		(at 139.7 110.49 180)
		(effects
			(font
				(size 1.27 1.27)
			)
			(justify right bottom)
		)
	)
	(label "Data_2_IN_N"
		(at 261.62 68.58 0)
		(effects
			(font
				(size 1.27 1.27)
			)
			(justify left bottom)
		)
	)
	(label "REFCLK+"
		(at 261.62 104.14 0)
		(effects
			(font
				(size 1.27 1.27)
			)
			(justify left bottom)
		)
	)
	(label "REFCLK+"
		(at 139.7 87.63 180)
		(effects
			(font
				(size 1.27 1.27)
			)
			(justify right bottom)
		)
	)
	(label "Data_3_IN_P"
		(at 139.7 128.27 180)
		(effects
			(font
				(size 1.27 1.27)
			)
			(justify right bottom)
		)
	)
	(label "Data_1_IN_P"
		(at 139.7 107.95 180)
		(effects
			(font
				(size 1.27 1.27)
			)
			(justify right bottom)
		)
	)
	(label "Data_0_OUT_P"
		(at 261.62 97.79 0)
		(effects
			(font
				(size 1.27 1.27)
			)
			(justify left bottom)
		)
	)
	(label "+3V3"
		(at 64.77 203.2 0)
		(effects
			(font
				(size 1.27 1.27)
			)
			(justify left bottom)
		)
	)
	(label "+3V3"
		(at 139.7 77.47 180)
		(effects
			(font
				(size 1.27 1.27)
			)
			(justify right bottom)
		)
	)
	(label "PWRGD"
		(at 335.28 54.61 180)
		(effects
			(font
				(size 1.27 1.27)
			)
			(justify right bottom)
		)
	)
	(label "+3V3_AUX"
		(at 125.73 203.2 180)
		(effects
			(font
				(size 1.27 1.27)
			)
			(justify right bottom)
		)
	)
	(label "Data_3_OUT_P"
		(at 261.62 59.69 0)
		(effects
			(font
				(size 1.27 1.27)
			)
			(justify left bottom)
		)
	)
	(label "Data_0_IN_N"
		(at 261.62 93.98 0)
		(effects
			(font
				(size 1.27 1.27)
			)
			(justify left bottom)
		)
	)
	(label "WAKE#"
		(at 335.28 59.69 180)
		(effects
			(font
				(size 1.27 1.27)
			)
			(justify right bottom)
		)
	)
	(label "+3V3"
		(at 261.62 49.53 0)
		(effects
			(font
				(size 1.27 1.27)
			)
			(justify left bottom)
		)
	)
	(label "Data_0_OUT_N"
		(at 71.12 92.71 0)
		(effects
			(font
				(size 1.27 1.27)
			)
			(justify left bottom)
		)
	)
	(label "+3V3"
		(at 139.7 74.93 180)
		(effects
			(font
				(size 1.27 1.27)
			)
			(justify right bottom)
		)
	)
	(label "Data_2_IN_P"
		(at 261.62 66.04 0)
		(effects
			(font
				(size 1.27 1.27)
			)
			(justify left bottom)
		)
	)
	(label "+3V3"
		(at 138.43 203.2 0)
		(effects
			(font
				(size 1.27 1.27)
			)
			(justify left bottom)
		)
	)
	(label "REFCLK-"
		(at 139.7 90.17 180)
		(effects
			(font
				(size 1.27 1.27)
			)
			(justify right bottom)
		)
	)
	(label "+3V3_AUX"
		(at 71.12 77.47 0)
		(effects
			(font
				(size 1.27 1.27)
			)
			(justify left bottom)
		)
	)
	(label "Data_0_OUT_N"
		(at 261.62 100.33 0)
		(effects
			(font
				(size 1.27 1.27)
			)
			(justify left bottom)
		)
	)
	(label "Data_2_IN_P"
		(at 139.7 118.11 180)
		(effects
			(font
				(size 1.27 1.27)
			)
			(justify right bottom)
		)
	)
	(label "Data_1_IN_P"
		(at 261.62 78.74 0)
		(effects
			(font
				(size 1.27 1.27)
			)
			(justify left bottom)
		)
	)
	(label "Data_1_OUT_P"
		(at 71.12 102.87 0)
		(effects
			(font
				(size 1.27 1.27)
			)
			(justify left bottom)
		)
	)
	(label "Data_3_OUT_N"
		(at 71.12 125.73 0)
		(effects
			(font
				(size 1.27 1.27)
			)
			(justify left bottom)
		)
	)
	(label "Data_3_IN_N"
		(at 261.62 55.88 0)
		(effects
			(font
				(size 1.27 1.27)
			)
			(justify left bottom)
		)
	)
	(label "Data_2_OUT_P"
		(at 261.62 72.39 0)
		(effects
			(font
				(size 1.27 1.27)
			)
			(justify left bottom)
		)
	)
	(label "Data_1_OUT_N"
		(at 261.62 87.63 0)
		(effects
			(font
				(size 1.27 1.27)
			)
			(justify left bottom)
		)
	)
	(label "Data_0_IN_N"
		(at 139.7 97.79 180)
		(effects
			(font
				(size 1.27 1.27)
			)
			(justify right bottom)
		)
	)
	(label "Data_2_OUT_N"
		(at 261.62 74.93 0)
		(effects
			(font
				(size 1.27 1.27)
			)
			(justify left bottom)
		)
	)
	(label "+3V3"
		(at 71.12 72.39 0)
		(effects
			(font
				(size 1.27 1.27)
			)
			(justify left bottom)
		)
	)
	(label "Data_0_OUT_P"
		(at 71.12 90.17 0)
		(effects
			(font
				(size 1.27 1.27)
			)
			(justify left bottom)
		)
	)
	(label "Data_1_IN_N"
		(at 261.62 81.28 0)
		(effects
			(font
				(size 1.27 1.27)
			)
			(justify left bottom)
		)
	)
	(label "Data_2_OUT_N"
		(at 71.12 115.57 0)
		(effects
			(font
				(size 1.27 1.27)
			)
			(justify left bottom)
		)
	)
	(label "Data_3_IN_P"
		(at 261.62 53.34 0)
		(effects
			(font
				(size 1.27 1.27)
			)
			(justify left bottom)
		)
	)
	(label "REFCLK-"
		(at 261.62 106.68 0)
		(effects
			(font
				(size 1.27 1.27)
			)
			(justify left bottom)
		)
	)
	(label "WAKE#"
		(at 53.34 80.01 0)
		(effects
			(font
				(size 1.27 1.27)
			)
			(justify left bottom)
		)
	)
	(label "Data_3_OUT_N"
		(at 261.62 62.23 0)
		(effects
			(font
				(size 1.27 1.27)
			)
			(justify left bottom)
		)
	)
	(label "PWRGD"
		(at 156.21 80.01 180)
		(effects
			(font
				(size 1.27 1.27)
			)
			(justify right bottom)
		)
	)
	(label "Data_3_OUT_P"
		(at 71.12 123.19 0)
		(effects
			(font
				(size 1.27 1.27)
			)
			(justify left bottom)
		)
	)
	(symbol
		(lib_id "antmicroEdgeConnectors:PCB-Edge_M.2_Key-M")
		(at 279.4 49.53 0)
		(unit 1)
		(exclude_from_sim no)
		(in_bom no)
		(on_board yes)
		(dnp no)
		(fields_autoplaced yes)
		(property "Reference" "J2"
			(at 298.45 41.91 0)
			(effects
				(font
					(size 1.524 1.524)
				)
			)
		)
		(property "Value" "PCB-Edge_M.2_Key-M"
			(at 298.45 44.45 0)
			(effects
				(font
					(size 1.27 1.27)
					(thickness 0.15)
				)
			)
		)
		(property "Footprint" "antmicro-footprints:PCB-Edge_M.2_Key-M"
			(at 332.74 57.15 0)
			(effects
				(font
					(size 1.27 1.27)
					(thickness 0.15)
				)
				(justify left bottom)
				(hide yes)
			)
		)
		(property "Datasheet" "https://www.amphenol-icc.com/media/wysiwyg/files/drawing/10130618.pdf"
			(at 332.74 59.69 0)
			(effects
				(font
					(size 1.27 1.27)
					(thickness 0.15)
				)
				(justify left bottom)
				(hide yes)
			)
		)
		(property "Description" "PCB Edge for M.2 key M"
			(at 279.4 49.53 0)
			(effects
				(font
					(size 1.27 1.27)
				)
				(hide yes)
			)
		)
		(property "Author" "Antmicro"
			(at 332.74 62.23 0)
			(effects
				(font
					(size 1.27 1.27)
					(thickness 0.15)
				)
				(justify left bottom)
				(hide yes)
			)
		)
		(property "License" "Apache-2.0"
			(at 332.74 64.77 0)
			(effects
				(font
					(size 1.27 1.27)
					(thickness 0.15)
				)
				(justify left bottom)
				(hide yes)
			)
		)
		(property "Public" "False"
			(at 332.74 67.31 0)
			(effects
				(font
					(size 1.27 1.27)
				)
				(justify left bottom)
				(hide yes)
			)
		)
		(pin "17"
		)
		(pin "18"
		)
		(pin "19"
		)
		(pin "2"
		)
		(pin "20"
		)
		(pin "21"
		)
		(pin "22"
		)
		(pin "23"
		)
		(pin "24"
		)
		(pin "25"
		)
		(pin "26"
		)
		(pin "27"
		)
		(pin "28"
		)
		(pin "29"
		)
		(pin "3"
		)
		(pin "1"
		)
		(pin "10"
		)
		(pin "11"
		)
		(pin "12"
		)
		(pin "13"
		)
		(pin "14"
		)
		(pin "15"
		)
		(pin "16"
		)
		(pin "30"
		)
		(pin "31"
		)
		(pin "32"
		)
		(pin "33"
		)
		(pin "34"
		)
		(pin "35"
		)
		(pin "36"
		)
		(pin "37"
		)
		(pin "38"
		)
		(pin "39"
		)
		(pin "4"
		)
		(pin "40"
		)
		(pin "41"
			(alternate "PERn0")
		)
		(pin "42"
		)
		(pin "43"
			(alternate "PERp0")
		)
		(pin "44"
		)
		(pin "45"
		)
		(pin "46"
		)
		(pin "47"
			(alternate "PETn0")
		)
		(pin "48"
		)
		(pin "49"
			(alternate "PETp0")
		)
		(pin "5"
		)
		(pin "50"
		)
		(pin "51"
		)
		(pin "52"
		)
		(pin "53"
		)
		(pin "54"
		)
		(pin "55"
		)
		(pin "56"
		)
		(pin "57"
		)
		(pin "58"
		)
		(pin "6"
		)
		(pin "67"
		)
		(pin "68"
		)
		(pin "69"
		)
		(pin "7"
		)
		(pin "70"
		)
		(pin "71"
		)
		(pin "72"
		)
		(pin "73"
		)
		(pin "74"
		)
		(pin "75"
		)
		(pin "8"
		)
		(pin "9"
		)
		(instances
			(project "m2-pcie-adapter"
				(path ""
					(reference "J2")
					(unit 1)
				)
			)
		)
	)
	(symbol
		(lib_id "antmicroPciConnectors:Socket_Samtec_PCIE_PCIe-x4_PCIE-064-02-X-D-EMSX")
		(at 88.9 54.61 0)
		(unit 1)
		(exclude_from_sim no)
		(in_bom yes)
		(on_board yes)
		(dnp no)
		(fields_autoplaced yes)
		(property "Reference" "J1"
			(at 105.41 46.99 0)
			(effects
				(font
					(size 1.27 1.27)
				)
			)
		)
		(property "Value" "Socket_Samtec_PCIE_PCIe-x4_PCIE-064-02-X-D-EMSX"
			(at 105.41 44.45 0)
			(effects
				(font
					(size 1.27 1.27)
				)
				(hide yes)
			)
		)
		(property "Footprint" "antmicro-footprints:Socket_Samtec_PCIE_PCIe-x4_PCIE-064-02-X-D-EMSX"
			(at 137.16 64.77 0)
			(effects
				(font
					(size 1.27 1.27)
					(thickness 0.15)
				)
				(justify left bottom)
				(hide yes)
			)
		)
		(property "Datasheet" "http://www.farnell.com/datasheets/2048385.pdf?_ga=2.224413790.550525831.1572511829-156563690.1566371002&_gac=1.194368863.1572511829.Cj0KCQjwjOrtBRCcARIsAEq4rW4MDAz553xUSGW1I2S05saoepO8CZq5otyVO6_gct6IiE-jnZiday4aAmKSEALw_wcB"
			(at 137.16 67.31 0)
			(effects
				(font
					(size 1.27 1.27)
					(thickness 0.15)
				)
				(justify left bottom)
				(hide yes)
			)
		)
		(property "Description" "PCIe x4 connector"
			(at 88.9 54.61 0)
			(effects
				(font
					(size 1.27 1.27)
				)
				(hide yes)
			)
		)
		(property "MPN" "PCIE-064-02-X-D-EMSX"
			(at 105.41 49.53 0)
			(effects
				(font
					(size 1.27 1.27)
					(thickness 0.15)
				)
				(hide yes)
			)
		)
		(property "Manufacturer" "Samtec"
			(at 137.16 69.85 0)
			(effects
				(font
					(size 1.27 1.27)
					(thickness 0.15)
				)
				(justify left bottom)
				(hide yes)
			)
		)
		(property "Author" "Antmicro"
			(at 137.16 72.39 0)
			(effects
				(font
					(size 1.27 1.27)
					(thickness 0.15)
				)
				(justify left bottom)
				(hide yes)
			)
		)
		(property "License" "Apache-2.0"
			(at 137.16 74.93 0)
			(effects
				(font
					(size 1.27 1.27)
					(thickness 0.15)
				)
				(justify left bottom)
				(hide yes)
			)
		)
		(pin "A1"
		)
		(pin "A10"
		)
		(pin "A11"
		)
		(pin "A12"
		)
		(pin "A13"
		)
		(pin "A14"
		)
		(pin "A15"
		)
		(pin "A16"
		)
		(pin "A17"
		)
		(pin "A18"
		)
		(pin "A19"
		)
		(pin "A2"
		)
		(pin "A20"
		)
		(pin "A21"
		)
		(pin "A22"
		)
		(pin "A23"
		)
		(pin "A24"
		)
		(pin "A25"
		)
		(pin "A26"
		)
		(pin "A27"
		)
		(pin "A28"
		)
		(pin "A29"
		)
		(pin "A3"
		)
		(pin "A30"
		)
		(pin "A31"
		)
		(pin "A32"
		)
		(pin "A4"
		)
		(pin "A5"
		)
		(pin "A6"
		)
		(pin "A7"
		)
		(pin "A8"
		)
		(pin "A9"
		)
		(pin "B1"
		)
		(pin "B10"
		)
		(pin "B11"
		)
		(pin "B12"
		)
		(pin "B13"
		)
		(pin "B14"
		)
		(pin "B15"
		)
		(pin "B16"
		)
		(pin "B17"
		)
		(pin "B18"
		)
		(pin "B19"
		)
		(pin "B2"
		)
		(pin "B20"
		)
		(pin "B21"
		)
		(pin "B22"
		)
		(pin "B23"
		)
		(pin "B24"
		)
		(pin "B25"
		)
		(pin "B26"
		)
		(pin "B27"
		)
		(pin "B28"
		)
		(pin "B29"
		)
		(pin "B3"
		)
		(pin "B30"
		)
		(pin "B31"
		)
		(pin "B32"
		)
		(pin "B4"
		)
		(pin "B5"
		)
		(pin "B6"
		)
		(pin "B7"
		)
		(pin "B8"
		)
		(pin "B9"
		)
		(instances
			(project "m2-pcie-adapter"
				(path ""
					(reference "J1")
					(unit 1)
				)
			)
		)
	)
	(symbol
		(lib_id "antmicropower:+12V")
		(at 85.09 46.99 0)
		(unit 1)
		(exclude_from_sim no)
		(in_bom yes)
		(on_board yes)
		(dnp no)
		(property "Reference" "#PWR0101"
			(at 85.09 50.8 0)
			(effects
				(font
					(size 1.27 1.27)
				)
				(hide yes)
			)
		)
		(property "Value" "+12V"
			(at 85.471 42.5958 0)
			(effects
				(font
					(size 1.27 1.27)
				)
			)
		)
		(property "Footprint" ""
			(at 85.09 46.99 0)
			(effects
				(font
					(size 1.27 1.27)
				)
				(hide yes)
			)
		)
		(property "Datasheet" ""
			(at 85.09 46.99 0)
			(effects
				(font
					(size 1.27 1.27)
				)
				(hide yes)
			)
		)
		(property "Description" ""
			(at 85.09 46.99 0)
			(effects
				(font
					(size 1.27 1.27)
				)
				(hide yes)
			)
		)
		(pin "1"
		)
		(instances
			(project "m2-pcie-adapter"
				(path ""
					(reference "#PWR0101")
					(unit 1)
				)
			)
		)
	)
	(symbol
		(lib_id "antmicropower:+12V")
		(at 125.73 46.99 0)
		(unit 1)
		(exclude_from_sim no)
		(in_bom yes)
		(on_board yes)
		(dnp no)
		(property "Reference" "#PWR0102"
			(at 125.73 50.8 0)
			(effects
				(font
					(size 1.27 1.27)
				)
				(hide yes)
			)
		)
		(property "Value" "+12V"
			(at 126.111 42.5958 0)
			(effects
				(font
					(size 1.27 1.27)
				)
			)
		)
		(property "Footprint" ""
			(at 125.73 46.99 0)
			(effects
				(font
					(size 1.27 1.27)
				)
				(hide yes)
			)
		)
		(property "Datasheet" ""
			(at 125.73 46.99 0)
			(effects
				(font
					(size 1.27 1.27)
				)
				(hide yes)
			)
		)
		(property "Description" ""
			(at 125.73 46.99 0)
			(effects
				(font
					(size 1.27 1.27)
				)
				(hide yes)
			)
		)
		(pin "1"
		)
		(instances
			(project "m2-pcie-adapter"
				(path ""
					(reference "#PWR0102")
					(unit 1)
				)
			)
		)
	)
	(symbol
		(lib_id "antmicropower:+12V")
		(at 39.37 201.93 0)
		(unit 1)
		(exclude_from_sim no)
		(in_bom yes)
		(on_board yes)
		(dnp no)
		(property "Reference" "#PWR0103"
			(at 39.37 205.74 0)
			(effects
				(font
					(size 1.27 1.27)
				)
				(hide yes)
			)
		)
		(property "Value" "+12V"
			(at 39.751 197.5358 0)
			(effects
				(font
					(size 1.27 1.27)
				)
			)
		)
		(property "Footprint" ""
			(at 39.37 201.93 0)
			(effects
				(font
					(size 1.27 1.27)
				)
				(hide yes)
			)
		)
		(property "Datasheet" ""
			(at 39.37 201.93 0)
			(effects
				(font
					(size 1.27 1.27)
				)
				(hide yes)
			)
		)
		(property "Description" ""
			(at 39.37 201.93 0)
			(effects
				(font
					(size 1.27 1.27)
				)
				(hide yes)
			)
		)
		(pin "1"
		)
		(instances
			(project "m2-pcie-adapter"
				(path ""
					(reference "#PWR0103")
					(unit 1)
				)
			)
		)
	)
	(symbol
		(lib_id "antmicroResistors0402:R_0R_0402")
		(at 90.17 203.2 0)
		(unit 1)
		(exclude_from_sim no)
		(in_bom yes)
		(on_board yes)
		(dnp no)
		(property "Reference" "R1"
			(at 92.71 200.66 0)
			(effects
				(font
					(size 1.524 1.524)
				)
			)
		)
		(property "Value" "R_0R_0402"
			(at 90.17 207.01 0)
			(effects
				(font
					(size 1.524 1.524)
				)
				(hide yes)
			)
		)
		(property "Footprint" "antmicro-footprints:R_0402_1005Metric"
			(at 95.25 198.12 0)
			(effects
				(font
					(size 1.524 1.524)
				)
				(justify left)
				(hide yes)
			)
		)
		(property "Datasheet" "https://industrial.panasonic.com/cdbs/www-data/pdf/RDA0000/AOA0000C301.pdf"
			(at 90.17 203.2 0)
			(effects
				(font
					(size 1.27 1.27)
				)
				(hide yes)
			)
		)
		(property "Description" "SMD Chip Resistor, Jumper, 0 ohm, 100 mW, 0402 [1005 Metric], Thick Film, General Purpose"
			(at 90.17 203.2 0)
			(effects
				(font
					(size 1.27 1.27)
				)
				(hide yes)
			)
		)
		(property "Manufacturer" "Panasonic"
			(at 95.25 193.04 0)
			(effects
				(font
					(size 1.524 1.524)
				)
				(justify left)
				(hide yes)
			)
		)
		(property "MPN" "ERJ2GE0R00X"
			(at 95.25 195.58 0)
			(effects
				(font
					(size 1.524 1.524)
				)
				(justify left)
				(hide yes)
			)
		)
		(property "Val" "0R"
			(at 92.71 203.2 0)
			(effects
				(font
					(size 1.27 1.27)
				)
				(hide yes)
			)
		)
		(property "License" "Apache-2.0"
			(at 110.49 228.6 0)
			(effects
				(font
					(size 1.27 1.27)
					(thickness 0.15)
				)
				(justify left bottom)
				(hide yes)
			)
		)
		(property "Author" "Antmicro"
			(at 110.49 231.14 0)
			(effects
				(font
					(size 1.27 1.27)
					(thickness 0.15)
				)
				(justify left bottom)
				(hide yes)
			)
		)
		(property "Tolerance" "~"
			(at 110.49 213.36 0)
			(effects
				(font
					(size 1.27 1.27)
				)
				(justify left bottom)
				(hide yes)
			)
		)
		(property "Current" "1A"
			(at 110.49 233.68 0)
			(effects
				(font
					(size 1.27 1.27)
					(thickness 0.15)
				)
				(justify left bottom)
				(hide yes)
			)
		)
		(property "Public" "False"
			(at 110.49 233.68 0)
			(effects
				(font
					(size 1.27 1.27)
				)
				(justify left bottom)
				(hide yes)
			)
		)
		(pin "1"
		)
		(pin "2"
		)
		(instances
			(project "m2-pcie-adapter"
				(path ""
					(reference "R1")
					(unit 1)
				)
			)
		)
	)
	(symbol
		(lib_id "antmicroCapacitors0402:C_100n_16V_X7R_0402")
		(at 39.37 208.28 270)
		(unit 1)
		(exclude_from_sim no)
		(in_bom yes)
		(on_board yes)
		(dnp no)
		(fields_autoplaced yes)
		(property "Reference" "C1"
			(at 41.91 209.5563 90)
			(effects
				(font
					(size 1.524 1.524)
				)
				(justify left)
			)
		)
		(property "Value" "C_100n_16V_X7R_0402"
			(at 35.56 208.28 0)
			(effects
				(font
					(size 1.524 1.524)
				)
				(hide yes)
			)
		)
		(property "Footprint" "antmicro-footprints:C_0402_1005Metric"
			(at 13.97 223.52 0)
			(effects
				(font
					(size 1.27 1.27)
					(thickness 0.15)
				)
				(justify left bottom)
				(hide yes)
			)
		)
		(property "Datasheet" "https://www.kemet.com/en/us/capacitors/product/C0402C104J4RAC7411.html"
			(at 11.43 223.52 0)
			(effects
				(font
					(size 1.27 1.27)
					(thickness 0.15)
				)
				(justify left bottom)
				(hide yes)
			)
		)
		(property "Description" "SMD Multilayer Ceramic Capacitor, 100nF, 50V, 0402, ±5%, X7R"
			(at 39.37 208.28 0)
			(effects
				(font
					(size 1.27 1.27)
				)
				(hide yes)
			)
		)
		(property "Manufacturer" "KEMET"
			(at 24.13 223.52 0)
			(effects
				(font
					(size 1.27 1.27)
					(thickness 0.15)
				)
				(justify left bottom)
				(hide yes)
			)
		)
		(property "MPN" "C0402C104J4RAC7411"
			(at 8.89 223.52 0)
			(effects
				(font
					(size 1.27 1.27)
					(thickness 0.15)
				)
				(justify left bottom)
				(hide yes)
			)
		)
		(property "Val" "100n"
			(at 41.91 212.0963 90)
			(effects
				(font
					(size 1.27 1.27)
					(thickness 0.15)
				)
				(justify left)
				(hide yes)
			)
		)
		(property "Voltage" "16V"
			(at 29.21 223.52 0)
			(effects
				(font
					(size 1.27 1.27)
					(thickness 0.15)
				)
				(justify left bottom)
				(hide yes)
			)
		)
		(property "Dielectric" "X7R"
			(at 26.67 223.52 0)
			(effects
				(font
					(size 1.27 1.27)
					(thickness 0.15)
				)
				(justify left bottom)
				(hide yes)
			)
		)
		(property "License" "Apache-2.0"
			(at 21.59 223.52 0)
			(effects
				(font
					(size 1.27 1.27)
					(thickness 0.15)
				)
				(justify left bottom)
				(hide yes)
			)
		)
		(property "Author" "Antmicro"
			(at 19.05 223.52 0)
			(effects
				(font
					(size 1.27 1.27)
					(thickness 0.15)
				)
				(justify left bottom)
				(hide yes)
			)
		)
		(pin "1"
		)
		(pin "2"
		)
		(instances
			(project "m2-pcie-adapter"
				(path ""
					(reference "C1")
					(unit 1)
				)
			)
		)
	)
	(symbol
		(lib_id "antmicropower:GND")
		(at 39.37 213.36 0)
		(unit 1)
		(exclude_from_sim no)
		(in_bom yes)
		(on_board yes)
		(dnp no)
		(property "Reference" "#PWR0104"
			(at 39.37 219.71 0)
			(effects
				(font
					(size 1.27 1.27)
				)
				(hide yes)
			)
		)
		(property "Value" "GND"
			(at 39.497 217.7542 0)
			(effects
				(font
					(size 1.27 1.27)
				)
			)
		)
		(property "Footprint" ""
			(at 39.37 213.36 0)
			(effects
				(font
					(size 1.27 1.27)
				)
				(hide yes)
			)
		)
		(property "Datasheet" ""
			(at 39.37 213.36 0)
			(effects
				(font
					(size 1.27 1.27)
				)
				(hide yes)
			)
		)
		(property "Description" ""
			(at 39.37 213.36 0)
			(effects
				(font
					(size 1.27 1.27)
				)
				(hide yes)
			)
		)
		(property "Author" "Antmicro"
			(at 48.26 220.98 0)
			(effects
				(font
					(size 1.27 1.27)
					(thickness 0.15)
				)
				(justify left bottom)
				(hide yes)
			)
		)
		(property "License" "Apache-2.0"
			(at 48.26 223.52 0)
			(effects
				(font
					(size 1.27 1.27)
					(thickness 0.15)
				)
				(justify left bottom)
				(hide yes)
			)
		)
		(pin "1"
		)
		(instances
			(project "m2-pcie-adapter"
				(path ""
					(reference "#PWR0104")
					(unit 1)
				)
			)
		)
	)
	(symbol
		(lib_id "antmicroResistors0402:R_0R_0402")
		(at 322.58 57.15 0)
		(unit 1)
		(exclude_from_sim no)
		(in_bom yes)
		(on_board yes)
		(dnp no)
		(property "Reference" "R2"
			(at 321.31 55.88 0)
			(effects
				(font
					(size 1.524 1.524)
				)
			)
		)
		(property "Value" "R_0R_0402"
			(at 322.58 60.96 0)
			(effects
				(font
					(size 1.524 1.524)
				)
				(hide yes)
			)
		)
		(property "Footprint" "antmicro-footprints:R_0402_1005Metric"
			(at 327.66 52.07 0)
			(effects
				(font
					(size 1.524 1.524)
				)
				(justify left)
				(hide yes)
			)
		)
		(property "Datasheet" "https://industrial.panasonic.com/cdbs/www-data/pdf/RDA0000/AOA0000C301.pdf"
			(at 322.58 57.15 0)
			(effects
				(font
					(size 1.27 1.27)
				)
				(hide yes)
			)
		)
		(property "Description" "SMD Chip Resistor, Jumper, 0 ohm, 100 mW, 0402 [1005 Metric], Thick Film, General Purpose"
			(at 322.58 57.15 0)
			(effects
				(font
					(size 1.27 1.27)
				)
				(hide yes)
			)
		)
		(property "Manufacturer" "Panasonic"
			(at 327.66 46.99 0)
			(effects
				(font
					(size 1.524 1.524)
				)
				(justify left)
				(hide yes)
			)
		)
		(property "MPN" "ERJ2GE0R00X"
			(at 327.66 49.53 0)
			(effects
				(font
					(size 1.524 1.524)
				)
				(justify left)
				(hide yes)
			)
		)
		(property "Val" "0R"
			(at 328.93 55.88 0)
			(effects
				(font
					(size 1.27 1.27)
				)
				(hide yes)
			)
		)
		(property "License" "Apache-2.0"
			(at 342.9 82.55 0)
			(effects
				(font
					(size 1.27 1.27)
					(thickness 0.15)
				)
				(justify left bottom)
				(hide yes)
			)
		)
		(property "Author" "Antmicro"
			(at 342.9 85.09 0)
			(effects
				(font
					(size 1.27 1.27)
					(thickness 0.15)
				)
				(justify left bottom)
				(hide yes)
			)
		)
		(property "Tolerance" "~"
			(at 342.9 67.31 0)
			(effects
				(font
					(size 1.27 1.27)
				)
				(justify left bottom)
				(hide yes)
			)
		)
		(property "Current" "1A"
			(at 342.9 87.63 0)
			(effects
				(font
					(size 1.27 1.27)
					(thickness 0.15)
				)
				(justify left bottom)
				(hide yes)
			)
		)
		(property "Public" "False"
			(at 342.9 87.63 0)
			(effects
				(font
					(size 1.27 1.27)
				)
				(justify left bottom)
				(hide yes)
			)
		)
		(pin "1"
		)
		(pin "2"
		)
		(instances
			(project "m2-pcie-adapter"
				(path ""
					(reference "R2")
					(unit 1)
				)
			)
		)
	)
	(symbol
		(lib_id "antmicroCapacitors0402:C_100n_16V_X7R_0402")
		(at 101.6 208.28 270)
		(unit 1)
		(exclude_from_sim no)
		(in_bom yes)
		(on_board yes)
		(dnp no)
		(fields_autoplaced yes)
		(property "Reference" "C5"
			(at 104.14 209.5563 90)
			(effects
				(font
					(size 1.524 1.524)
				)
				(justify left)
			)
		)
		(property "Value" "C_100n_16V_X7R_0402"
			(at 97.79 208.28 0)
			(effects
				(font
					(size 1.524 1.524)
				)
				(hide yes)
			)
		)
		(property "Footprint" "antmicro-footprints:C_0402_1005Metric"
			(at 76.2 223.52 0)
			(effects
				(font
					(size 1.27 1.27)
					(thickness 0.15)
				)
				(justify left bottom)
				(hide yes)
			)
		)
		(property "Datasheet" "https://www.kemet.com/en/us/capacitors/product/C0402C104J4RAC7411.html"
			(at 73.66 223.52 0)
			(effects
				(font
					(size 1.27 1.27)
					(thickness 0.15)
				)
				(justify left bottom)
				(hide yes)
			)
		)
		(property "Description" "SMD Multilayer Ceramic Capacitor, 100nF, 50V, 0402, ±5%, X7R"
			(at 101.6 208.28 0)
			(effects
				(font
					(size 1.27 1.27)
				)
				(hide yes)
			)
		)
		(property "Manufacturer" "KEMET"
			(at 86.36 223.52 0)
			(effects
				(font
					(size 1.27 1.27)
					(thickness 0.15)
				)
				(justify left bottom)
				(hide yes)
			)
		)
		(property "MPN" "C0402C104J4RAC7411"
			(at 71.12 223.52 0)
			(effects
				(font
					(size 1.27 1.27)
					(thickness 0.15)
				)
				(justify left bottom)
				(hide yes)
			)
		)
		(property "Val" "100n"
			(at 104.14 212.0963 90)
			(effects
				(font
					(size 1.27 1.27)
					(thickness 0.15)
				)
				(justify left)
				(hide yes)
			)
		)
		(property "Voltage" "16V"
			(at 91.44 223.52 0)
			(effects
				(font
					(size 1.27 1.27)
					(thickness 0.15)
				)
				(justify left bottom)
				(hide yes)
			)
		)
		(property "Dielectric" "X7R"
			(at 88.9 223.52 0)
			(effects
				(font
					(size 1.27 1.27)
					(thickness 0.15)
				)
				(justify left bottom)
				(hide yes)
			)
		)
		(property "License" "Apache-2.0"
			(at 83.82 223.52 0)
			(effects
				(font
					(size 1.27 1.27)
					(thickness 0.15)
				)
				(justify left bottom)
				(hide yes)
			)
		)
		(property "Author" "Antmicro"
			(at 81.28 223.52 0)
			(effects
				(font
					(size 1.27 1.27)
					(thickness 0.15)
				)
				(justify left bottom)
				(hide yes)
			)
		)
		(pin "1"
		)
		(pin "2"
		)
		(instances
			(project "m2-pcie-adapter"
				(path ""
					(reference "C5")
					(unit 1)
				)
			)
		)
	)
	(symbol
		(lib_id "antmicroCapacitors0402:C_100n_16V_X7R_0402")
		(at 83.82 208.28 270)
		(unit 1)
		(exclude_from_sim no)
		(in_bom yes)
		(on_board yes)
		(dnp no)
		(fields_autoplaced yes)
		(property "Reference" "C4"
			(at 86.36 209.5563 90)
			(effects
				(font
					(size 1.524 1.524)
				)
				(justify left)
			)
		)
		(property "Value" "C_100n_16V_X7R_0402"
			(at 80.01 208.28 0)
			(effects
				(font
					(size 1.524 1.524)
				)
				(hide yes)
			)
		)
		(property "Footprint" "antmicro-footprints:C_0402_1005Metric"
			(at 58.42 223.52 0)
			(effects
				(font
					(size 1.27 1.27)
					(thickness 0.15)
				)
				(justify left bottom)
				(hide yes)
			)
		)
		(property "Datasheet" "https://www.kemet.com/en/us/capacitors/product/C0402C104J4RAC7411.html"
			(at 55.88 223.52 0)
			(effects
				(font
					(size 1.27 1.27)
					(thickness 0.15)
				)
				(justify left bottom)
				(hide yes)
			)
		)
		(property "Description" "SMD Multilayer Ceramic Capacitor, 100nF, 50V, 0402, ±5%, X7R"
			(at 83.82 208.28 0)
			(effects
				(font
					(size 1.27 1.27)
				)
				(hide yes)
			)
		)
		(property "Manufacturer" "KEMET"
			(at 68.58 223.52 0)
			(effects
				(font
					(size 1.27 1.27)
					(thickness 0.15)
				)
				(justify left bottom)
				(hide yes)
			)
		)
		(property "MPN" "C0402C104J4RAC7411"
			(at 53.34 223.52 0)
			(effects
				(font
					(size 1.27 1.27)
					(thickness 0.15)
				)
				(justify left bottom)
				(hide yes)
			)
		)
		(property "Val" "100n"
			(at 86.36 212.0963 90)
			(effects
				(font
					(size 1.27 1.27)
					(thickness 0.15)
				)
				(justify left)
				(hide yes)
			)
		)
		(property "Voltage" "16V"
			(at 73.66 223.52 0)
			(effects
				(font
					(size 1.27 1.27)
					(thickness 0.15)
				)
				(justify left bottom)
				(hide yes)
			)
		)
		(property "Dielectric" "X7R"
			(at 71.12 223.52 0)
			(effects
				(font
					(size 1.27 1.27)
					(thickness 0.15)
				)
				(justify left bottom)
				(hide yes)
			)
		)
		(property "License" "Apache-2.0"
			(at 66.04 223.52 0)
			(effects
				(font
					(size 1.27 1.27)
					(thickness 0.15)
				)
				(justify left bottom)
				(hide yes)
			)
		)
		(property "Author" "Antmicro"
			(at 63.5 223.52 0)
			(effects
				(font
					(size 1.27 1.27)
					(thickness 0.15)
				)
				(justify left bottom)
				(hide yes)
			)
		)
		(pin "1"
		)
		(pin "2"
		)
		(instances
			(project "m2-pcie-adapter"
				(path ""
					(reference "C4")
					(unit 1)
				)
			)
		)
	)
	(symbol
		(lib_id "antmicroCapacitors0603:C_1u_0603")
		(at 73.66 208.28 270)
		(unit 1)
		(exclude_from_sim no)
		(in_bom yes)
		(on_board yes)
		(dnp no)
		(fields_autoplaced yes)
		(property "Reference" "C3"
			(at 76.2 209.5563 90)
			(effects
				(font
					(size 1.524 1.524)
				)
				(justify left)
			)
		)
		(property "Value" "C_1u_0603"
			(at 69.85 208.28 0)
			(effects
				(font
					(size 1.524 1.524)
				)
				(hide yes)
			)
		)
		(property "Footprint" "antmicro-footprints:C_0603_1608Metric"
			(at 78.74 213.36 0)
			(effects
				(font
					(size 1.524 1.524)
				)
				(justify left)
				(hide yes)
			)
		)
		(property "Datasheet" "https://spicat.kyocera-avx.com/product/mlcc/chartview/0603YD105KAT2A/"
			(at 73.66 208.28 0)
			(effects
				(font
					(size 1.27 1.27)
				)
				(hide yes)
			)
		)
		(property "Description" "SMD Multilayer Ceramic Capacitor, 1 µF, 16 V, 0603 [1608 Metric], ± 10%, X5R, AVX 0603 MLCC"
			(at 73.66 208.28 0)
			(effects
				(font
					(size 1.27 1.27)
				)
				(hide yes)
			)
		)
		(property "Manufacturer" "KYOCERA AVX"
			(at 83.82 213.36 0)
			(effects
				(font
					(size 1.524 1.524)
				)
				(justify left)
				(hide yes)
			)
		)
		(property "MPN" "0603YD105KAT2A"
			(at 81.28 213.36 0)
			(effects
				(font
					(size 1.524 1.524)
				)
				(justify left)
				(hide yes)
			)
		)
		(property "Val" "1u"
			(at 76.2 212.0963 90)
			(effects
				(font
					(size 1.27 1.27)
				)
				(justify left)
				(hide yes)
			)
		)
		(property "License" "Apache-2.0"
			(at 50.8 228.6 0)
			(effects
				(font
					(size 1.27 1.27)
					(thickness 0.15)
				)
				(justify left bottom)
				(hide yes)
			)
		)
		(property "Author" "Antmicro"
			(at 48.26 228.6 0)
			(effects
				(font
					(size 1.27 1.27)
					(thickness 0.15)
				)
				(justify left bottom)
				(hide yes)
			)
		)
		(property "Voltage" ""
			(at 45.72 228.6 0)
			(effects
				(font
					(size 1.27 1.27)
				)
				(justify left bottom)
				(hide yes)
			)
		)
		(property "Dielectric" ""
			(at 43.18 228.6 0)
			(effects
				(font
					(size 1.27 1.27)
				)
				(justify left bottom)
				(hide yes)
			)
		)
		(property "Public" "False"
			(at 40.64 228.6 0)
			(effects
				(font
					(size 1.27 1.27)
				)
				(justify left bottom)
				(hide yes)
			)
		)
		(pin "1"
		)
		(pin "2"
		)
		(instances
			(project "m2-pcie-adapter"
				(path ""
					(reference "C3")
					(unit 1)
				)
			)
		)
	)
	(symbol
		(lib_id "antmicroCapacitors0603:C_1u_0603")
		(at 111.76 208.28 270)
		(unit 1)
		(exclude_from_sim no)
		(in_bom yes)
		(on_board yes)
		(dnp no)
		(fields_autoplaced yes)
		(property "Reference" "C6"
			(at 114.3 209.5563 90)
			(effects
				(font
					(size 1.524 1.524)
				)
				(justify left)
			)
		)
		(property "Value" "C_1u_0603"
			(at 107.95 208.28 0)
			(effects
				(font
					(size 1.524 1.524)
				)
				(hide yes)
			)
		)
		(property "Footprint" "antmicro-footprints:C_0603_1608Metric"
			(at 116.84 213.36 0)
			(effects
				(font
					(size 1.524 1.524)
				)
				(justify left)
				(hide yes)
			)
		)
		(property "Datasheet" "https://spicat.kyocera-avx.com/product/mlcc/chartview/0603YD105KAT2A/"
			(at 111.76 208.28 0)
			(effects
				(font
					(size 1.27 1.27)
				)
				(hide yes)
			)
		)
		(property "Description" "SMD Multilayer Ceramic Capacitor, 1 µF, 16 V, 0603 [1608 Metric], ± 10%, X5R, AVX 0603 MLCC"
			(at 111.76 208.28 0)
			(effects
				(font
					(size 1.27 1.27)
				)
				(hide yes)
			)
		)
		(property "Manufacturer" "KYOCERA AVX"
			(at 121.92 213.36 0)
			(effects
				(font
					(size 1.524 1.524)
				)
				(justify left)
				(hide yes)
			)
		)
		(property "MPN" "0603YD105KAT2A"
			(at 119.38 213.36 0)
			(effects
				(font
					(size 1.524 1.524)
				)
				(justify left)
				(hide yes)
			)
		)
		(property "Val" "1u"
			(at 114.3 212.0963 90)
			(effects
				(font
					(size 1.27 1.27)
				)
				(justify left)
				(hide yes)
			)
		)
		(property "License" "Apache-2.0"
			(at 88.9 228.6 0)
			(effects
				(font
					(size 1.27 1.27)
					(thickness 0.15)
				)
				(justify left bottom)
				(hide yes)
			)
		)
		(property "Author" "Antmicro"
			(at 86.36 228.6 0)
			(effects
				(font
					(size 1.27 1.27)
					(thickness 0.15)
				)
				(justify left bottom)
				(hide yes)
			)
		)
		(property "Voltage" ""
			(at 83.82 228.6 0)
			(effects
				(font
					(size 1.27 1.27)
				)
				(justify left bottom)
				(hide yes)
			)
		)
		(property "Dielectric" ""
			(at 81.28 228.6 0)
			(effects
				(font
					(size 1.27 1.27)
				)
				(justify left bottom)
				(hide yes)
			)
		)
		(property "Public" "False"
			(at 78.74 228.6 0)
			(effects
				(font
					(size 1.27 1.27)
				)
				(justify left bottom)
				(hide yes)
			)
		)
		(pin "1"
		)
		(pin "2"
		)
		(instances
			(project "m2-pcie-adapter"
				(path ""
					(reference "C6")
					(unit 1)
				)
			)
		)
	)
	(symbol
		(lib_id "antmicroCapacitors0603:C_1u_0603")
		(at 50.8 208.28 270)
		(unit 1)
		(exclude_from_sim no)
		(in_bom yes)
		(on_board yes)
		(dnp no)
		(fields_autoplaced yes)
		(property "Reference" "C2"
			(at 53.34 209.5563 90)
			(effects
				(font
					(size 1.524 1.524)
				)
				(justify left)
			)
		)
		(property "Value" "C_1u_0603"
			(at 46.99 208.28 0)
			(effects
				(font
					(size 1.524 1.524)
				)
				(hide yes)
			)
		)
		(property "Footprint" "antmicro-footprints:C_0603_1608Metric"
			(at 55.88 213.36 0)
			(effects
				(font
					(size 1.524 1.524)
				)
				(justify left)
				(hide yes)
			)
		)
		(property "Datasheet" "https://spicat.kyocera-avx.com/product/mlcc/chartview/0603YD105KAT2A/"
			(at 50.8 208.28 0)
			(effects
				(font
					(size 1.27 1.27)
				)
				(hide yes)
			)
		)
		(property "Description" "SMD Multilayer Ceramic Capacitor, 1 µF, 16 V, 0603 [1608 Metric], ± 10%, X5R, AVX 0603 MLCC"
			(at 50.8 208.28 0)
			(effects
				(font
					(size 1.27 1.27)
				)
				(hide yes)
			)
		)
		(property "Manufacturer" "KYOCERA AVX"
			(at 60.96 213.36 0)
			(effects
				(font
					(size 1.524 1.524)
				)
				(justify left)
				(hide yes)
			)
		)
		(property "MPN" "0603YD105KAT2A"
			(at 58.42 213.36 0)
			(effects
				(font
					(size 1.524 1.524)
				)
				(justify left)
				(hide yes)
			)
		)
		(property "Val" "1u"
			(at 53.34 212.0963 90)
			(effects
				(font
					(size 1.27 1.27)
				)
				(justify left)
				(hide yes)
			)
		)
		(property "License" "Apache-2.0"
			(at 27.94 228.6 0)
			(effects
				(font
					(size 1.27 1.27)
					(thickness 0.15)
				)
				(justify left bottom)
				(hide yes)
			)
		)
		(property "Author" "Antmicro"
			(at 25.4 228.6 0)
			(effects
				(font
					(size 1.27 1.27)
					(thickness 0.15)
				)
				(justify left bottom)
				(hide yes)
			)
		)
		(property "Voltage" ""
			(at 22.86 228.6 0)
			(effects
				(font
					(size 1.27 1.27)
				)
				(justify left bottom)
				(hide yes)
			)
		)
		(property "Dielectric" ""
			(at 20.32 228.6 0)
			(effects
				(font
					(size 1.27 1.27)
				)
				(justify left bottom)
				(hide yes)
			)
		)
		(property "Public" "False"
			(at 17.78 228.6 0)
			(effects
				(font
					(size 1.27 1.27)
				)
				(justify left bottom)
				(hide yes)
			)
		)
		(pin "1"
		)
		(pin "2"
		)
		(instances
			(project "m2-pcie-adapter"
				(path ""
					(reference "C2")
					(unit 1)
				)
			)
		)
	)
	(symbol
		(lib_id "antmicropower:GND")
		(at 85.09 142.24 0)
		(unit 1)
		(exclude_from_sim no)
		(in_bom yes)
		(on_board yes)
		(dnp no)
		(property "Reference" "#PWR0106"
			(at 85.09 148.59 0)
			(effects
				(font
					(size 1.27 1.27)
				)
				(hide yes)
			)
		)
		(property "Value" "GND"
			(at 85.217 146.6342 0)
			(effects
				(font
					(size 1.27 1.27)
				)
			)
		)
		(property "Footprint" ""
			(at 85.09 142.24 0)
			(effects
				(font
					(size 1.27 1.27)
				)
				(hide yes)
			)
		)
		(property "Datasheet" ""
			(at 85.09 142.24 0)
			(effects
				(font
					(size 1.27 1.27)
				)
				(hide yes)
			)
		)
		(property "Description" ""
			(at 85.09 142.24 0)
			(effects
				(font
					(size 1.27 1.27)
				)
				(hide yes)
			)
		)
		(property "Author" "Antmicro"
			(at 93.98 149.86 0)
			(effects
				(font
					(size 1.27 1.27)
					(thickness 0.15)
				)
				(justify left bottom)
				(hide yes)
			)
		)
		(property "License" "Apache-2.0"
			(at 93.98 152.4 0)
			(effects
				(font
					(size 1.27 1.27)
					(thickness 0.15)
				)
				(justify left bottom)
				(hide yes)
			)
		)
		(pin "1"
		)
		(instances
			(project "m2-pcie-adapter"
				(path ""
					(reference "#PWR0106")
					(unit 1)
				)
			)
		)
	)
	(symbol
		(lib_id "antmicropower:GND")
		(at 125.73 142.24 0)
		(unit 1)
		(exclude_from_sim no)
		(in_bom yes)
		(on_board yes)
		(dnp no)
		(property "Reference" "#PWR0107"
			(at 125.73 148.59 0)
			(effects
				(font
					(size 1.27 1.27)
				)
				(hide yes)
			)
		)
		(property "Value" "GND"
			(at 125.857 146.6342 0)
			(effects
				(font
					(size 1.27 1.27)
				)
			)
		)
		(property "Footprint" ""
			(at 125.73 142.24 0)
			(effects
				(font
					(size 1.27 1.27)
				)
				(hide yes)
			)
		)
		(property "Datasheet" ""
			(at 125.73 142.24 0)
			(effects
				(font
					(size 1.27 1.27)
				)
				(hide yes)
			)
		)
		(property "Description" ""
			(at 125.73 142.24 0)
			(effects
				(font
					(size 1.27 1.27)
				)
				(hide yes)
			)
		)
		(property "Author" "Antmicro"
			(at 134.62 149.86 0)
			(effects
				(font
					(size 1.27 1.27)
					(thickness 0.15)
				)
				(justify left bottom)
				(hide yes)
			)
		)
		(property "License" "Apache-2.0"
			(at 134.62 152.4 0)
			(effects
				(font
					(size 1.27 1.27)
					(thickness 0.15)
				)
				(justify left bottom)
				(hide yes)
			)
		)
		(pin "1"
		)
		(instances
			(project "m2-pcie-adapter"
				(path ""
					(reference "#PWR0107")
					(unit 1)
				)
			)
		)
	)
	(symbol
		(lib_id "antmicropower:GND")
		(at 320.04 114.3 0)
		(unit 1)
		(exclude_from_sim no)
		(in_bom yes)
		(on_board yes)
		(dnp no)
		(property "Reference" "#PWR0108"
			(at 320.04 120.65 0)
			(effects
				(font
					(size 1.27 1.27)
				)
				(hide yes)
			)
		)
		(property "Value" "GND"
			(at 320.167 118.6942 0)
			(effects
				(font
					(size 1.27 1.27)
				)
			)
		)
		(property "Footprint" ""
			(at 320.04 114.3 0)
			(effects
				(font
					(size 1.27 1.27)
				)
				(hide yes)
			)
		)
		(property "Datasheet" ""
			(at 320.04 114.3 0)
			(effects
				(font
					(size 1.27 1.27)
				)
				(hide yes)
			)
		)
		(property "Description" ""
			(at 320.04 114.3 0)
			(effects
				(font
					(size 1.27 1.27)
				)
				(hide yes)
			)
		)
		(property "Author" "Antmicro"
			(at 328.93 121.92 0)
			(effects
				(font
					(size 1.27 1.27)
					(thickness 0.15)
				)
				(justify left bottom)
				(hide yes)
			)
		)
		(property "License" "Apache-2.0"
			(at 328.93 124.46 0)
			(effects
				(font
					(size 1.27 1.27)
					(thickness 0.15)
				)
				(justify left bottom)
				(hide yes)
			)
		)
		(pin "1"
		)
		(instances
			(project "m2-pcie-adapter"
				(path ""
					(reference "#PWR0108")
					(unit 1)
				)
			)
		)
	)
	(symbol
		(lib_id "antmicroCapacitors0603:C_1u_0603")
		(at 147.32 208.28 270)
		(unit 1)
		(exclude_from_sim no)
		(in_bom yes)
		(on_board yes)
		(dnp no)
		(fields_autoplaced yes)
		(property "Reference" "C7"
			(at 149.86 209.5563 90)
			(effects
				(font
					(size 1.524 1.524)
				)
				(justify left)
			)
		)
		(property "Value" "C_1u_0603"
			(at 143.51 208.28 0)
			(effects
				(font
					(size 1.524 1.524)
				)
				(hide yes)
			)
		)
		(property "Footprint" "antmicro-footprints:C_0603_1608Metric"
			(at 152.4 213.36 0)
			(effects
				(font
					(size 1.524 1.524)
				)
				(justify left)
				(hide yes)
			)
		)
		(property "Datasheet" "https://spicat.kyocera-avx.com/product/mlcc/chartview/0603YD105KAT2A/"
			(at 147.32 208.28 0)
			(effects
				(font
					(size 1.27 1.27)
				)
				(hide yes)
			)
		)
		(property "Description" "SMD Multilayer Ceramic Capacitor, 1 µF, 16 V, 0603 [1608 Metric], ± 10%, X5R, AVX 0603 MLCC"
			(at 147.32 208.28 0)
			(effects
				(font
					(size 1.27 1.27)
				)
				(hide yes)
			)
		)
		(property "Manufacturer" "KYOCERA AVX"
			(at 157.48 213.36 0)
			(effects
				(font
					(size 1.524 1.524)
				)
				(justify left)
				(hide yes)
			)
		)
		(property "MPN" "0603YD105KAT2A"
			(at 154.94 213.36 0)
			(effects
				(font
					(size 1.524 1.524)
				)
				(justify left)
				(hide yes)
			)
		)
		(property "Val" "1u"
			(at 149.86 212.0963 90)
			(effects
				(font
					(size 1.27 1.27)
				)
				(justify left)
				(hide yes)
			)
		)
		(property "License" "Apache-2.0"
			(at 124.46 228.6 0)
			(effects
				(font
					(size 1.27 1.27)
					(thickness 0.15)
				)
				(justify left bottom)
				(hide yes)
			)
		)
		(property "Author" "Antmicro"
			(at 121.92 228.6 0)
			(effects
				(font
					(size 1.27 1.27)
					(thickness 0.15)
				)
				(justify left bottom)
				(hide yes)
			)
		)
		(property "Voltage" ""
			(at 119.38 228.6 0)
			(effects
				(font
					(size 1.27 1.27)
				)
				(justify left bottom)
				(hide yes)
			)
		)
		(property "Dielectric" ""
			(at 116.84 228.6 0)
			(effects
				(font
					(size 1.27 1.27)
				)
				(justify left bottom)
				(hide yes)
			)
		)
		(property "Public" "False"
			(at 114.3 228.6 0)
			(effects
				(font
					(size 1.27 1.27)
				)
				(justify left bottom)
				(hide yes)
			)
		)
		(pin "1"
		)
		(pin "2"
		)
		(instances
			(project "m2-pcie-adapter"
				(path ""
					(reference "C7")
					(unit 1)
				)
			)
		)
	)
	(symbol
		(lib_id "antmicropower:GND")
		(at 147.32 213.36 0)
		(unit 1)
		(exclude_from_sim no)
		(in_bom yes)
		(on_board yes)
		(dnp no)
		(property "Reference" "#PWR0109"
			(at 147.32 219.71 0)
			(effects
				(font
					(size 1.27 1.27)
				)
				(hide yes)
			)
		)
		(property "Value" "GND"
			(at 147.447 217.7542 0)
			(effects
				(font
					(size 1.27 1.27)
				)
			)
		)
		(property "Footprint" ""
			(at 147.32 213.36 0)
			(effects
				(font
					(size 1.27 1.27)
				)
				(hide yes)
			)
		)
		(property "Datasheet" ""
			(at 147.32 213.36 0)
			(effects
				(font
					(size 1.27 1.27)
				)
				(hide yes)
			)
		)
		(property "Description" ""
			(at 147.32 213.36 0)
			(effects
				(font
					(size 1.27 1.27)
				)
				(hide yes)
			)
		)
		(property "Author" "Antmicro"
			(at 156.21 220.98 0)
			(effects
				(font
					(size 1.27 1.27)
					(thickness 0.15)
				)
				(justify left bottom)
				(hide yes)
			)
		)
		(property "License" "Apache-2.0"
			(at 156.21 223.52 0)
			(effects
				(font
					(size 1.27 1.27)
					(thickness 0.15)
				)
				(justify left bottom)
				(hide yes)
			)
		)
		(pin "1"
		)
		(instances
			(project "m2-pcie-adapter"
				(path ""
					(reference "#PWR0109")
					(unit 1)
				)
			)
		)
	)
	(symbol
		(lib_id "antmicroCapacitors0603:C_1u_0603")
		(at 157.48 208.28 270)
		(unit 1)
		(exclude_from_sim no)
		(in_bom yes)
		(on_board yes)
		(dnp no)
		(fields_autoplaced yes)
		(property "Reference" "C8"
			(at 160.02 209.5563 90)
			(effects
				(font
					(size 1.524 1.524)
				)
				(justify left)
			)
		)
		(property "Value" "C_1u_0603"
			(at 153.67 208.28 0)
			(effects
				(font
					(size 1.524 1.524)
				)
				(hide yes)
			)
		)
		(property "Footprint" "antmicro-footprints:C_0603_1608Metric"
			(at 162.56 213.36 0)
			(effects
				(font
					(size 1.524 1.524)
				)
				(justify left)
				(hide yes)
			)
		)
		(property "Datasheet" "https://spicat.kyocera-avx.com/product/mlcc/chartview/0603YD105KAT2A/"
			(at 157.48 208.28 0)
			(effects
				(font
					(size 1.27 1.27)
				)
				(hide yes)
			)
		)
		(property "Description" "SMD Multilayer Ceramic Capacitor, 1 µF, 16 V, 0603 [1608 Metric], ± 10%, X5R, AVX 0603 MLCC"
			(at 157.48 208.28 0)
			(effects
				(font
					(size 1.27 1.27)
				)
				(hide yes)
			)
		)
		(property "Manufacturer" "KYOCERA AVX"
			(at 167.64 213.36 0)
			(effects
				(font
					(size 1.524 1.524)
				)
				(justify left)
				(hide yes)
			)
		)
		(property "MPN" "0603YD105KAT2A"
			(at 165.1 213.36 0)
			(effects
				(font
					(size 1.524 1.524)
				)
				(justify left)
				(hide yes)
			)
		)
		(property "Val" "1u"
			(at 160.02 212.0963 90)
			(effects
				(font
					(size 1.27 1.27)
				)
				(justify left)
				(hide yes)
			)
		)
		(property "License" "Apache-2.0"
			(at 134.62 228.6 0)
			(effects
				(font
					(size 1.27 1.27)
					(thickness 0.15)
				)
				(justify left bottom)
				(hide yes)
			)
		)
		(property "Author" "Antmicro"
			(at 132.08 228.6 0)
			(effects
				(font
					(size 1.27 1.27)
					(thickness 0.15)
				)
				(justify left bottom)
				(hide yes)
			)
		)
		(property "Voltage" ""
			(at 129.54 228.6 0)
			(effects
				(font
					(size 1.27 1.27)
				)
				(justify left bottom)
				(hide yes)
			)
		)
		(property "Dielectric" ""
			(at 127 228.6 0)
			(effects
				(font
					(size 1.27 1.27)
				)
				(justify left bottom)
				(hide yes)
			)
		)
		(property "Public" "False"
			(at 124.46 228.6 0)
			(effects
				(font
					(size 1.27 1.27)
				)
				(justify left bottom)
				(hide yes)
			)
		)
		(pin "1"
		)
		(pin "2"
		)
		(instances
			(project "m2-pcie-adapter"
				(path ""
					(reference "C8")
					(unit 1)
				)
			)
		)
	)
	(symbol
		(lib_id "antmicroCapacitors0603:C_1u_0603")
		(at 168.91 208.28 270)
		(unit 1)
		(exclude_from_sim no)
		(in_bom yes)
		(on_board yes)
		(dnp no)
		(fields_autoplaced yes)
		(property "Reference" "C9"
			(at 171.45 209.5563 90)
			(effects
				(font
					(size 1.524 1.524)
				)
				(justify left)
			)
		)
		(property "Value" "C_1u_0603"
			(at 165.1 208.28 0)
			(effects
				(font
					(size 1.524 1.524)
				)
				(hide yes)
			)
		)
		(property "Footprint" "antmicro-footprints:C_0603_1608Metric"
			(at 173.99 213.36 0)
			(effects
				(font
					(size 1.524 1.524)
				)
				(justify left)
				(hide yes)
			)
		)
		(property "Datasheet" "https://spicat.kyocera-avx.com/product/mlcc/chartview/0603YD105KAT2A/"
			(at 168.91 208.28 0)
			(effects
				(font
					(size 1.27 1.27)
				)
				(hide yes)
			)
		)
		(property "Description" "SMD Multilayer Ceramic Capacitor, 1 µF, 16 V, 0603 [1608 Metric], ± 10%, X5R, AVX 0603 MLCC"
			(at 168.91 208.28 0)
			(effects
				(font
					(size 1.27 1.27)
				)
				(hide yes)
			)
		)
		(property "Manufacturer" "KYOCERA AVX"
			(at 179.07 213.36 0)
			(effects
				(font
					(size 1.524 1.524)
				)
				(justify left)
				(hide yes)
			)
		)
		(property "MPN" "0603YD105KAT2A"
			(at 176.53 213.36 0)
			(effects
				(font
					(size 1.524 1.524)
				)
				(justify left)
				(hide yes)
			)
		)
		(property "Val" "1u"
			(at 171.45 212.0963 90)
			(effects
				(font
					(size 1.27 1.27)
				)
				(justify left)
				(hide yes)
			)
		)
		(property "License" "Apache-2.0"
			(at 146.05 228.6 0)
			(effects
				(font
					(size 1.27 1.27)
					(thickness 0.15)
				)
				(justify left bottom)
				(hide yes)
			)
		)
		(property "Author" "Antmicro"
			(at 143.51 228.6 0)
			(effects
				(font
					(size 1.27 1.27)
					(thickness 0.15)
				)
				(justify left bottom)
				(hide yes)
			)
		)
		(property "Voltage" ""
			(at 140.97 228.6 0)
			(effects
				(font
					(size 1.27 1.27)
				)
				(justify left bottom)
				(hide yes)
			)
		)
		(property "Dielectric" ""
			(at 138.43 228.6 0)
			(effects
				(font
					(size 1.27 1.27)
				)
				(justify left bottom)
				(hide yes)
			)
		)
		(property "Public" "False"
			(at 135.89 228.6 0)
			(effects
				(font
					(size 1.27 1.27)
				)
				(justify left bottom)
				(hide yes)
			)
		)
		(pin "1"
		)
		(pin "2"
		)
		(instances
			(project "m2-pcie-adapter"
				(path ""
					(reference "C9")
					(unit 1)
				)
			)
		)
	)
	(symbol
		(lib_id "antmicropower:GND")
		(at 157.48 213.36 0)
		(unit 1)
		(exclude_from_sim no)
		(in_bom yes)
		(on_board yes)
		(dnp no)
		(property "Reference" "#PWR0105"
			(at 157.48 219.71 0)
			(effects
				(font
					(size 1.27 1.27)
				)
				(hide yes)
			)
		)
		(property "Value" "GND"
			(at 157.607 217.7542 0)
			(effects
				(font
					(size 1.27 1.27)
				)
			)
		)
		(property "Footprint" ""
			(at 157.48 213.36 0)
			(effects
				(font
					(size 1.27 1.27)
				)
				(hide yes)
			)
		)
		(property "Datasheet" ""
			(at 157.48 213.36 0)
			(effects
				(font
					(size 1.27 1.27)
				)
				(hide yes)
			)
		)
		(property "Description" ""
			(at 157.48 213.36 0)
			(effects
				(font
					(size 1.27 1.27)
				)
				(hide yes)
			)
		)
		(property "Author" "Antmicro"
			(at 166.37 220.98 0)
			(effects
				(font
					(size 1.27 1.27)
					(thickness 0.15)
				)
				(justify left bottom)
				(hide yes)
			)
		)
		(property "License" "Apache-2.0"
			(at 166.37 223.52 0)
			(effects
				(font
					(size 1.27 1.27)
					(thickness 0.15)
				)
				(justify left bottom)
				(hide yes)
			)
		)
		(pin "1"
		)
		(instances
			(project "m2-pcie-adapter"
				(path ""
					(reference "#PWR0105")
					(unit 1)
				)
			)
		)
	)
	(symbol
		(lib_id "antmicropower:GND")
		(at 168.91 213.36 0)
		(unit 1)
		(exclude_from_sim no)
		(in_bom yes)
		(on_board yes)
		(dnp no)
		(property "Reference" "#PWR0116"
			(at 168.91 219.71 0)
			(effects
				(font
					(size 1.27 1.27)
				)
				(hide yes)
			)
		)
		(property "Value" "GND"
			(at 169.037 217.7542 0)
			(effects
				(font
					(size 1.27 1.27)
				)
			)
		)
		(property "Footprint" ""
			(at 168.91 213.36 0)
			(effects
				(font
					(size 1.27 1.27)
				)
				(hide yes)
			)
		)
		(property "Datasheet" ""
			(at 168.91 213.36 0)
			(effects
				(font
					(size 1.27 1.27)
				)
				(hide yes)
			)
		)
		(property "Description" ""
			(at 168.91 213.36 0)
			(effects
				(font
					(size 1.27 1.27)
				)
				(hide yes)
			)
		)
		(property "Author" "Antmicro"
			(at 177.8 220.98 0)
			(effects
				(font
					(size 1.27 1.27)
					(thickness 0.15)
				)
				(justify left bottom)
				(hide yes)
			)
		)
		(property "License" "Apache-2.0"
			(at 177.8 223.52 0)
			(effects
				(font
					(size 1.27 1.27)
					(thickness 0.15)
				)
				(justify left bottom)
				(hide yes)
			)
		)
		(pin "1"
		)
		(instances
			(project "m2-pcie-adapter"
				(path ""
					(reference "#PWR0116")
					(unit 1)
				)
			)
		)
	)
	(symbol
		(lib_id "antmicropower:GND")
		(at 337.82 62.23 0)
		(unit 1)
		(exclude_from_sim no)
		(in_bom yes)
		(on_board yes)
		(dnp no)
		(property "Reference" "#PWR0110"
			(at 337.82 68.58 0)
			(effects
				(font
					(size 1.27 1.27)
				)
				(hide yes)
			)
		)
		(property "Value" "GND"
			(at 337.947 66.6242 0)
			(effects
				(font
					(size 1.27 1.27)
				)
			)
		)
		(property "Footprint" ""
			(at 337.82 62.23 0)
			(effects
				(font
					(size 1.27 1.27)
				)
				(hide yes)
			)
		)
		(property "Datasheet" ""
			(at 337.82 62.23 0)
			(effects
				(font
					(size 1.27 1.27)
				)
				(hide yes)
			)
		)
		(property "Description" ""
			(at 337.82 62.23 0)
			(effects
				(font
					(size 1.27 1.27)
				)
				(hide yes)
			)
		)
		(property "Author" "Antmicro"
			(at 346.71 69.85 0)
			(effects
				(font
					(size 1.27 1.27)
					(thickness 0.15)
				)
				(justify left bottom)
				(hide yes)
			)
		)
		(property "License" "Apache-2.0"
			(at 346.71 72.39 0)
			(effects
				(font
					(size 1.27 1.27)
					(thickness 0.15)
				)
				(justify left bottom)
				(hide yes)
			)
		)
		(pin "1"
		)
		(instances
			(project "m2-pcie-adapter"
				(path ""
					(reference "#PWR0110")
					(unit 1)
				)
			)
		)
	)
	(symbol
		(lib_id "antmicropower:GND")
		(at 73.66 213.36 0)
		(unit 1)
		(exclude_from_sim no)
		(in_bom yes)
		(on_board yes)
		(dnp no)
		(property "Reference" "#PWR0117"
			(at 73.66 219.71 0)
			(effects
				(font
					(size 1.27 1.27)
				)
				(hide yes)
			)
		)
		(property "Value" "GND"
			(at 73.787 217.7542 0)
			(effects
				(font
					(size 1.27 1.27)
				)
			)
		)
		(property "Footprint" ""
			(at 73.66 213.36 0)
			(effects
				(font
					(size 1.27 1.27)
				)
				(hide yes)
			)
		)
		(property "Datasheet" ""
			(at 73.66 213.36 0)
			(effects
				(font
					(size 1.27 1.27)
				)
				(hide yes)
			)
		)
		(property "Description" ""
			(at 73.66 213.36 0)
			(effects
				(font
					(size 1.27 1.27)
				)
				(hide yes)
			)
		)
		(property "Author" "Antmicro"
			(at 82.55 220.98 0)
			(effects
				(font
					(size 1.27 1.27)
					(thickness 0.15)
				)
				(justify left bottom)
				(hide yes)
			)
		)
		(property "License" "Apache-2.0"
			(at 82.55 223.52 0)
			(effects
				(font
					(size 1.27 1.27)
					(thickness 0.15)
				)
				(justify left bottom)
				(hide yes)
			)
		)
		(pin "1"
		)
		(instances
			(project "m2-pcie-adapter"
				(path ""
					(reference "#PWR0117")
					(unit 1)
				)
			)
		)
	)
	(symbol
		(lib_id "antmicropower:GND")
		(at 83.82 213.36 0)
		(unit 1)
		(exclude_from_sim no)
		(in_bom yes)
		(on_board yes)
		(dnp no)
		(property "Reference" "#PWR0118"
			(at 83.82 219.71 0)
			(effects
				(font
					(size 1.27 1.27)
				)
				(hide yes)
			)
		)
		(property "Value" "GND"
			(at 83.947 217.7542 0)
			(effects
				(font
					(size 1.27 1.27)
				)
			)
		)
		(property "Footprint" ""
			(at 83.82 213.36 0)
			(effects
				(font
					(size 1.27 1.27)
				)
				(hide yes)
			)
		)
		(property "Datasheet" ""
			(at 83.82 213.36 0)
			(effects
				(font
					(size 1.27 1.27)
				)
				(hide yes)
			)
		)
		(property "Description" ""
			(at 83.82 213.36 0)
			(effects
				(font
					(size 1.27 1.27)
				)
				(hide yes)
			)
		)
		(property "Author" "Antmicro"
			(at 92.71 220.98 0)
			(effects
				(font
					(size 1.27 1.27)
					(thickness 0.15)
				)
				(justify left bottom)
				(hide yes)
			)
		)
		(property "License" "Apache-2.0"
			(at 92.71 223.52 0)
			(effects
				(font
					(size 1.27 1.27)
					(thickness 0.15)
				)
				(justify left bottom)
				(hide yes)
			)
		)
		(pin "1"
		)
		(instances
			(project "m2-pcie-adapter"
				(path ""
					(reference "#PWR0118")
					(unit 1)
				)
			)
		)
	)
	(symbol
		(lib_id "antmicropower:GND")
		(at 101.6 213.36 0)
		(unit 1)
		(exclude_from_sim no)
		(in_bom yes)
		(on_board yes)
		(dnp no)
		(property "Reference" "#PWR0119"
			(at 101.6 219.71 0)
			(effects
				(font
					(size 1.27 1.27)
				)
				(hide yes)
			)
		)
		(property "Value" "GND"
			(at 101.727 217.7542 0)
			(effects
				(font
					(size 1.27 1.27)
				)
			)
		)
		(property "Footprint" ""
			(at 101.6 213.36 0)
			(effects
				(font
					(size 1.27 1.27)
				)
				(hide yes)
			)
		)
		(property "Datasheet" ""
			(at 101.6 213.36 0)
			(effects
				(font
					(size 1.27 1.27)
				)
				(hide yes)
			)
		)
		(property "Description" ""
			(at 101.6 213.36 0)
			(effects
				(font
					(size 1.27 1.27)
				)
				(hide yes)
			)
		)
		(property "Author" "Antmicro"
			(at 110.49 220.98 0)
			(effects
				(font
					(size 1.27 1.27)
					(thickness 0.15)
				)
				(justify left bottom)
				(hide yes)
			)
		)
		(property "License" "Apache-2.0"
			(at 110.49 223.52 0)
			(effects
				(font
					(size 1.27 1.27)
					(thickness 0.15)
				)
				(justify left bottom)
				(hide yes)
			)
		)
		(pin "1"
		)
		(instances
			(project "m2-pcie-adapter"
				(path ""
					(reference "#PWR0119")
					(unit 1)
				)
			)
		)
	)
	(symbol
		(lib_id "antmicropower:GND")
		(at 111.76 213.36 0)
		(unit 1)
		(exclude_from_sim no)
		(in_bom yes)
		(on_board yes)
		(dnp no)
		(property "Reference" "#PWR0120"
			(at 111.76 219.71 0)
			(effects
				(font
					(size 1.27 1.27)
				)
				(hide yes)
			)
		)
		(property "Value" "GND"
			(at 111.887 217.7542 0)
			(effects
				(font
					(size 1.27 1.27)
				)
			)
		)
		(property "Footprint" ""
			(at 111.76 213.36 0)
			(effects
				(font
					(size 1.27 1.27)
				)
				(hide yes)
			)
		)
		(property "Datasheet" ""
			(at 111.76 213.36 0)
			(effects
				(font
					(size 1.27 1.27)
				)
				(hide yes)
			)
		)
		(property "Description" ""
			(at 111.76 213.36 0)
			(effects
				(font
					(size 1.27 1.27)
				)
				(hide yes)
			)
		)
		(property "Author" "Antmicro"
			(at 120.65 220.98 0)
			(effects
				(font
					(size 1.27 1.27)
					(thickness 0.15)
				)
				(justify left bottom)
				(hide yes)
			)
		)
		(property "License" "Apache-2.0"
			(at 120.65 223.52 0)
			(effects
				(font
					(size 1.27 1.27)
					(thickness 0.15)
				)
				(justify left bottom)
				(hide yes)
			)
		)
		(pin "1"
		)
		(instances
			(project "m2-pcie-adapter"
				(path ""
					(reference "#PWR0120")
					(unit 1)
				)
			)
		)
	)
	(symbol
		(lib_id "antmicropower:+12V")
		(at 238.76 203.2 90)
		(mirror x)
		(unit 1)
		(exclude_from_sim no)
		(in_bom yes)
		(on_board yes)
		(dnp no)
		(fields_autoplaced yes)
		(property "Reference" "#PWR0111"
			(at 242.57 203.2 0)
			(effects
				(font
					(size 1.27 1.27)
				)
				(hide yes)
			)
		)
		(property "Value" "+12V"
			(at 237.49 200.66 90)
			(effects
				(font
					(size 1.27 1.27)
				)
			)
		)
		(property "Footprint" ""
			(at 238.76 203.2 0)
			(effects
				(font
					(size 1.27 1.27)
				)
				(hide yes)
			)
		)
		(property "Datasheet" ""
			(at 238.76 203.2 0)
			(effects
				(font
					(size 1.27 1.27)
				)
				(hide yes)
			)
		)
		(property "Description" ""
			(at 238.76 203.2 0)
			(effects
				(font
					(size 1.27 1.27)
				)
				(hide yes)
			)
		)
		(pin "1"
		)
		(instances
			(project "m2-pcie-adapter"
				(path ""
					(reference "#PWR0111")
					(unit 1)
				)
			)
		)
	)
	(symbol
		(lib_id "antmicropower:GND")
		(at 242.57 214.63 0)
		(mirror y)
		(unit 1)
		(exclude_from_sim no)
		(in_bom yes)
		(on_board yes)
		(dnp no)
		(fields_autoplaced yes)
		(property "Reference" "#PWR0112"
			(at 242.57 220.98 0)
			(effects
				(font
					(size 1.27 1.27)
				)
				(hide yes)
			)
		)
		(property "Value" "GND"
			(at 245.11 215.9 0)
			(effects
				(font
					(size 1.27 1.27)
				)
				(justify right)
			)
		)
		(property "Footprint" ""
			(at 242.57 214.63 0)
			(effects
				(font
					(size 1.27 1.27)
				)
				(hide yes)
			)
		)
		(property "Datasheet" ""
			(at 242.57 214.63 0)
			(effects
				(font
					(size 1.27 1.27)
				)
				(hide yes)
			)
		)
		(property "Description" ""
			(at 242.57 214.63 0)
			(effects
				(font
					(size 1.27 1.27)
				)
				(hide yes)
			)
		)
		(property "Author" "Antmicro"
			(at 233.68 222.25 0)
			(effects
				(font
					(size 1.27 1.27)
					(thickness 0.15)
				)
				(justify left bottom)
				(hide yes)
			)
		)
		(property "License" "Apache-2.0"
			(at 233.68 224.79 0)
			(effects
				(font
					(size 1.27 1.27)
					(thickness 0.15)
				)
				(justify left bottom)
				(hide yes)
			)
		)
		(pin "1"
		)
		(instances
			(project "m2-pcie-adapter"
				(path ""
					(reference "#PWR0112")
					(unit 1)
				)
			)
		)
	)
	(symbol
		(lib_id "antmicropower:+5V")
		(at 238.76 210.82 90)
		(mirror x)
		(unit 1)
		(exclude_from_sim no)
		(in_bom yes)
		(on_board yes)
		(dnp no)
		(fields_autoplaced yes)
		(property "Reference" "#PWR0113"
			(at 242.57 210.82 0)
			(effects
				(font
					(size 1.27 1.27)
				)
				(hide yes)
			)
		)
		(property "Value" "+5V"
			(at 237.49 208.28 90)
			(effects
				(font
					(size 1.27 1.27)
				)
			)
		)
		(property "Footprint" ""
			(at 238.76 210.82 0)
			(effects
				(font
					(size 1.27 1.27)
				)
				(hide yes)
			)
		)
		(property "Datasheet" ""
			(at 238.76 210.82 0)
			(effects
				(font
					(size 1.27 1.27)
				)
				(hide yes)
			)
		)
		(property "Description" ""
			(at 238.76 210.82 0)
			(effects
				(font
					(size 1.27 1.27)
				)
				(hide yes)
			)
		)
		(property "Author" "Antmicro"
			(at 246.38 226.06 0)
			(effects
				(font
					(size 1.27 1.27)
					(thickness 0.15)
				)
				(justify left bottom)
				(hide yes)
			)
		)
		(property "License" "Apache-2.0"
			(at 248.92 226.06 0)
			(effects
				(font
					(size 1.27 1.27)
					(thickness 0.15)
				)
				(justify left bottom)
				(hide yes)
			)
		)
		(pin "1"
		)
		(instances
			(project "m2-pcie-adapter"
				(path ""
					(reference "#PWR0113")
					(unit 1)
				)
			)
		)
	)
	(symbol
		(lib_id "antmicroWire2BoardConnectors:Molex_KK_1x4_22-05-3041_Horizontal")
		(at 243.84 203.2 0)
		(unit 1)
		(exclude_from_sim no)
		(in_bom yes)
		(on_board yes)
		(dnp yes)
		(fields_autoplaced yes)
		(property "Reference" "J3"
			(at 250.19 205.74 0)
			(effects
				(font
					(size 1.27 1.27)
				)
				(justify left)
			)
		)
		(property "Value" "Molex_KK_1x4_22-05-3041_Horizontal"
			(at 254 207.01 90)
			(effects
				(font
					(size 1.27 1.27)
				)
				(hide yes)
			)
		)
		(property "Footprint" "antmicro-footprints:Conn_Molex_KK_1x4_22-05-3041_Horizontal"
			(at 264.16 215.9 0)
			(effects
				(font
					(size 1.27 1.27)
					(thickness 0.15)
				)
				(justify left bottom)
				(hide yes)
			)
		)
		(property "Datasheet" "https://www.molex.com/content/dam/molex/molex-dot-com/products/automated/en-us/salesdrawingpdf/747/7478/022053041_sd.pdf?inline"
			(at 264.16 218.44 0)
			(effects
				(font
					(size 1.27 1.27)
					(thickness 0.15)
				)
				(justify left bottom)
				(hide yes)
			)
		)
		(property "Description" "Connector Header, THT,  4x1"
			(at 243.84 203.2 0)
			(effects
				(font
					(size 1.27 1.27)
				)
				(hide yes)
			)
		)
		(property "MPN" "22-05-3041"
			(at 250.19 208.28 0)
			(effects
				(font
					(size 1.27 1.27)
					(thickness 0.15)
				)
				(justify left)
				(hide yes)
			)
		)
		(property "Manufacturer" "Molex"
			(at 264.16 220.98 0)
			(effects
				(font
					(size 1.27 1.27)
					(thickness 0.15)
				)
				(justify left bottom)
				(hide yes)
			)
		)
		(property "Author" "Antmicro"
			(at 264.16 223.52 0)
			(effects
				(font
					(size 1.27 1.27)
					(thickness 0.15)
				)
				(justify left bottom)
				(hide yes)
			)
		)
		(property "License" "Apache-2.0"
			(at 264.16 226.06 0)
			(effects
				(font
					(size 1.27 1.27)
					(thickness 0.15)
				)
				(justify left bottom)
				(hide yes)
			)
		)
		(pin "1"
		)
		(pin "2"
		)
		(pin "3"
		)
		(pin "4"
		)
		(instances
			(project "m2-pcie-adapter"
				(path ""
					(reference "J3")
					(unit 1)
				)
			)
		)
	)
	(symbol
		(lib_id "antmicroResistors0402:R_0R_0402")
		(at 140.97 80.01 0)
		(unit 1)
		(exclude_from_sim no)
		(in_bom yes)
		(on_board yes)
		(dnp no)
		(property "Reference" "R4"
			(at 143.51 77.47 0)
			(effects
				(font
					(size 1.524 1.524)
				)
			)
		)
		(property "Value" "R_0R_0402"
			(at 140.97 83.82 0)
			(effects
				(font
					(size 1.524 1.524)
				)
				(hide yes)
			)
		)
		(property "Footprint" "antmicro-footprints:R_0402_1005Metric"
			(at 146.05 74.93 0)
			(effects
				(font
					(size 1.524 1.524)
				)
				(justify left)
				(hide yes)
			)
		)
		(property "Datasheet" "https://industrial.panasonic.com/cdbs/www-data/pdf/RDA0000/AOA0000C301.pdf"
			(at 140.97 80.01 0)
			(effects
				(font
					(size 1.27 1.27)
				)
				(hide yes)
			)
		)
		(property "Description" "SMD Chip Resistor, Jumper, 0 ohm, 100 mW, 0402 [1005 Metric], Thick Film, General Purpose"
			(at 140.97 80.01 0)
			(effects
				(font
					(size 1.27 1.27)
				)
				(hide yes)
			)
		)
		(property "Manufacturer" "Panasonic"
			(at 146.05 69.85 0)
			(effects
				(font
					(size 1.524 1.524)
				)
				(justify left)
				(hide yes)
			)
		)
		(property "MPN" "ERJ2GE0R00X"
			(at 146.05 72.39 0)
			(effects
				(font
					(size 1.524 1.524)
				)
				(justify left)
				(hide yes)
			)
		)
		(property "Val" "0R"
			(at 143.51 80.01 0)
			(effects
				(font
					(size 1.27 1.27)
				)
				(hide yes)
			)
		)
		(property "License" "Apache-2.0"
			(at 161.29 105.41 0)
			(effects
				(font
					(size 1.27 1.27)
					(thickness 0.15)
				)
				(justify left bottom)
				(hide yes)
			)
		)
		(property "Author" "Antmicro"
			(at 161.29 107.95 0)
			(effects
				(font
					(size 1.27 1.27)
					(thickness 0.15)
				)
				(justify left bottom)
				(hide yes)
			)
		)
		(property "Tolerance" "~"
			(at 161.29 90.17 0)
			(effects
				(font
					(size 1.27 1.27)
				)
				(justify left bottom)
				(hide yes)
			)
		)
		(property "Current" "1A"
			(at 161.29 110.49 0)
			(effects
				(font
					(size 1.27 1.27)
					(thickness 0.15)
				)
				(justify left bottom)
				(hide yes)
			)
		)
		(property "Public" "False"
			(at 161.29 110.49 0)
			(effects
				(font
					(size 1.27 1.27)
				)
				(justify left bottom)
				(hide yes)
			)
		)
		(pin "1"
		)
		(pin "2"
		)
		(instances
			(project "m2-pcie-adapter"
				(path ""
					(reference "R4")
					(unit 1)
				)
			)
		)
	)
	(symbol
		(lib_id "antmicroResistors0402:R_0R_0402")
		(at 63.5 80.01 0)
		(unit 1)
		(exclude_from_sim no)
		(in_bom yes)
		(on_board yes)
		(dnp no)
		(property "Reference" "R3"
			(at 66.04 77.47 0)
			(effects
				(font
					(size 1.524 1.524)
				)
			)
		)
		(property "Value" "R_0R_0402"
			(at 63.5 83.82 0)
			(effects
				(font
					(size 1.524 1.524)
				)
				(hide yes)
			)
		)
		(property "Footprint" "antmicro-footprints:R_0402_1005Metric"
			(at 68.58 74.93 0)
			(effects
				(font
					(size 1.524 1.524)
				)
				(justify left)
				(hide yes)
			)
		)
		(property "Datasheet" "https://industrial.panasonic.com/cdbs/www-data/pdf/RDA0000/AOA0000C301.pdf"
			(at 63.5 80.01 0)
			(effects
				(font
					(size 1.27 1.27)
				)
				(hide yes)
			)
		)
		(property "Description" "SMD Chip Resistor, Jumper, 0 ohm, 100 mW, 0402 [1005 Metric], Thick Film, General Purpose"
			(at 63.5 80.01 0)
			(effects
				(font
					(size 1.27 1.27)
				)
				(hide yes)
			)
		)
		(property "Manufacturer" "Panasonic"
			(at 68.58 69.85 0)
			(effects
				(font
					(size 1.524 1.524)
				)
				(justify left)
				(hide yes)
			)
		)
		(property "MPN" "ERJ2GE0R00X"
			(at 68.58 72.39 0)
			(effects
				(font
					(size 1.524 1.524)
				)
				(justify left)
				(hide yes)
			)
		)
		(property "Val" "0R"
			(at 66.04 80.01 0)
			(effects
				(font
					(size 1.27 1.27)
				)
				(hide yes)
			)
		)
		(property "License" "Apache-2.0"
			(at 83.82 105.41 0)
			(effects
				(font
					(size 1.27 1.27)
					(thickness 0.15)
				)
				(justify left bottom)
				(hide yes)
			)
		)
		(property "Author" "Antmicro"
			(at 83.82 107.95 0)
			(effects
				(font
					(size 1.27 1.27)
					(thickness 0.15)
				)
				(justify left bottom)
				(hide yes)
			)
		)
		(property "Tolerance" "~"
			(at 83.82 90.17 0)
			(effects
				(font
					(size 1.27 1.27)
				)
				(justify left bottom)
				(hide yes)
			)
		)
		(property "Current" "1A"
			(at 83.82 110.49 0)
			(effects
				(font
					(size 1.27 1.27)
					(thickness 0.15)
				)
				(justify left bottom)
				(hide yes)
			)
		)
		(property "Public" "False"
			(at 83.82 110.49 0)
			(effects
				(font
					(size 1.27 1.27)
				)
				(justify left bottom)
				(hide yes)
			)
		)
		(pin "1"
		)
		(pin "2"
		)
		(instances
			(project "m2-pcie-adapter"
				(path ""
					(reference "R3")
					(unit 1)
				)
			)
		)
	)
	(symbol
		(lib_id "antmicroPogoPins:Harwin_1x1_H3.5mm_Pad2.2mm_P70-1000045R")
		(at 234.95 228.6 0)
		(unit 1)
		(exclude_from_sim no)
		(in_bom yes)
		(on_board yes)
		(dnp no)
		(fields_autoplaced yes)
		(property "Reference" "J4"
			(at 251.46 227.33 0)
			(effects
				(font
					(size 1.27 1.27)
				)
				(justify left)
			)
		)
		(property "Value" "Harwin_1x1_H3.5mm_Pad2.2mm_P70-1000045R"
			(at 234.95 231.14 0)
			(effects
				(font
					(size 1.27 1.27)
				)
				(hide yes)
			)
		)
		(property "Footprint" "antmicro-footprints:Harwin_1x1_H3.5mm_Pad2.2mm_P70-1000045R"
			(at 262.89 238.76 0)
			(effects
				(font
					(size 1.27 1.27)
					(thickness 0.15)
				)
				(justify left bottom)
				(hide yes)
			)
		)
		(property "Datasheet" "https://eu.mouser.com/datasheet/2/181/P70_10X-1018735.pdf"
			(at 262.89 241.3 0)
			(effects
				(font
					(size 1.27 1.27)
					(thickness 0.15)
				)
				(justify left bottom)
				(hide yes)
			)
		)
		(property "Description" "Contact Spring Surface Mount"
			(at 234.95 228.6 0)
			(effects
				(font
					(size 1.27 1.27)
				)
				(hide yes)
			)
		)
		(property "MPN" "P70-1000045R"
			(at 251.46 229.87 0)
			(effects
				(font
					(size 1.27 1.27)
					(thickness 0.15)
				)
				(justify left)
				(hide yes)
			)
		)
		(property "Manufacturer" "Harwin"
			(at 262.89 243.84 0)
			(effects
				(font
					(size 1.27 1.27)
					(thickness 0.15)
				)
				(justify left bottom)
				(hide yes)
			)
		)
		(property "Author" "Antmicro"
			(at 262.89 246.38 0)
			(effects
				(font
					(size 1.27 1.27)
					(thickness 0.15)
				)
				(justify left bottom)
				(hide yes)
			)
		)
		(property "License" "Apache-2.0"
			(at 262.89 248.92 0)
			(effects
				(font
					(size 1.27 1.27)
					(thickness 0.15)
				)
				(justify left bottom)
				(hide yes)
			)
		)
		(pin "1"
		)
		(instances
			(project "m2-pcie-adapter"
				(path ""
					(reference "J4")
					(unit 1)
				)
			)
		)
	)
	(symbol
		(lib_id "antmicroPogoPins:Harwin_1x1_H3.5mm_Pad2.2mm_P70-1000045R")
		(at 234.95 237.49 0)
		(unit 1)
		(exclude_from_sim no)
		(in_bom yes)
		(on_board yes)
		(dnp no)
		(fields_autoplaced yes)
		(property "Reference" "J5"
			(at 250.825 236.22 0)
			(effects
				(font
					(size 1.27 1.27)
				)
				(justify left)
			)
		)
		(property "Value" "Harwin_1x1_H3.5mm_Pad2.2mm_P70-1000045R"
			(at 234.95 240.03 0)
			(effects
				(font
					(size 1.27 1.27)
				)
				(hide yes)
			)
		)
		(property "Footprint" "antmicro-footprints:Harwin_1x1_H3.5mm_Pad2.2mm_P70-1000045R"
			(at 262.89 247.65 0)
			(effects
				(font
					(size 1.27 1.27)
					(thickness 0.15)
				)
				(justify left bottom)
				(hide yes)
			)
		)
		(property "Datasheet" "https://eu.mouser.com/datasheet/2/181/P70_10X-1018735.pdf"
			(at 262.89 250.19 0)
			(effects
				(font
					(size 1.27 1.27)
					(thickness 0.15)
				)
				(justify left bottom)
				(hide yes)
			)
		)
		(property "Description" "Contact Spring Surface Mount"
			(at 234.95 237.49 0)
			(effects
				(font
					(size 1.27 1.27)
				)
				(hide yes)
			)
		)
		(property "MPN" "P70-1000045R"
			(at 250.825 238.76 0)
			(effects
				(font
					(size 1.27 1.27)
					(thickness 0.15)
				)
				(justify left)
				(hide yes)
			)
		)
		(property "Manufacturer" "Harwin"
			(at 262.89 252.73 0)
			(effects
				(font
					(size 1.27 1.27)
					(thickness 0.15)
				)
				(justify left bottom)
				(hide yes)
			)
		)
		(property "Author" "Antmicro"
			(at 262.89 255.27 0)
			(effects
				(font
					(size 1.27 1.27)
					(thickness 0.15)
				)
				(justify left bottom)
				(hide yes)
			)
		)
		(property "License" "Apache-2.0"
			(at 262.89 257.81 0)
			(effects
				(font
					(size 1.27 1.27)
					(thickness 0.15)
				)
				(justify left bottom)
				(hide yes)
			)
		)
		(pin "1"
		)
		(instances
			(project "m2-pcie-adapter"
				(path ""
					(reference "J5")
					(unit 1)
				)
			)
		)
	)
	(symbol
		(lib_id "antmicropower:+5V")
		(at 232.41 237.49 90)
		(unit 1)
		(exclude_from_sim no)
		(in_bom yes)
		(on_board yes)
		(dnp no)
		(fields_autoplaced yes)
		(property "Reference" "#PWR0114"
			(at 236.22 237.49 0)
			(effects
				(font
					(size 1.27 1.27)
				)
				(hide yes)
			)
		)
		(property "Value" "+5V"
			(at 231.14 234.95 90)
			(effects
				(font
					(size 1.27 1.27)
				)
			)
		)
		(property "Footprint" ""
			(at 232.41 237.49 0)
			(effects
				(font
					(size 1.27 1.27)
				)
				(hide yes)
			)
		)
		(property "Datasheet" ""
			(at 232.41 237.49 0)
			(effects
				(font
					(size 1.27 1.27)
				)
				(hide yes)
			)
		)
		(property "Description" ""
			(at 232.41 237.49 0)
			(effects
				(font
					(size 1.27 1.27)
				)
				(hide yes)
			)
		)
		(property "Author" "Antmicro"
			(at 240.03 222.25 0)
			(effects
				(font
					(size 1.27 1.27)
					(thickness 0.15)
				)
				(justify left bottom)
				(hide yes)
			)
		)
		(property "License" "Apache-2.0"
			(at 242.57 222.25 0)
			(effects
				(font
					(size 1.27 1.27)
					(thickness 0.15)
				)
				(justify left bottom)
				(hide yes)
			)
		)
		(pin "1"
		)
		(instances
			(project "m2-pcie-adapter"
				(path ""
					(reference "#PWR0114")
					(unit 1)
				)
			)
		)
	)
	(symbol
		(lib_id "antmicropower:+12V")
		(at 232.41 228.6 90)
		(unit 1)
		(exclude_from_sim no)
		(in_bom yes)
		(on_board yes)
		(dnp no)
		(fields_autoplaced yes)
		(property "Reference" "#PWR0115"
			(at 236.22 228.6 0)
			(effects
				(font
					(size 1.27 1.27)
				)
				(hide yes)
			)
		)
		(property "Value" "+12V"
			(at 231.14 226.06 90)
			(effects
				(font
					(size 1.27 1.27)
				)
			)
		)
		(property "Footprint" ""
			(at 232.41 228.6 0)
			(effects
				(font
					(size 1.27 1.27)
				)
				(hide yes)
			)
		)
		(property "Datasheet" ""
			(at 232.41 228.6 0)
			(effects
				(font
					(size 1.27 1.27)
				)
				(hide yes)
			)
		)
		(property "Description" ""
			(at 232.41 228.6 0)
			(effects
				(font
					(size 1.27 1.27)
				)
				(hide yes)
			)
		)
		(pin "1"
		)
		(instances
			(project "m2-pcie-adapter"
				(path ""
					(reference "#PWR0115")
					(unit 1)
				)
			)
		)
	)
	(symbol
		(lib_id "antmicroMechanicalParts:antmicro_logo")
		(at 97.79 276.86 0)
		(unit 1)
		(exclude_from_sim no)
		(in_bom yes)
		(on_board yes)
		(dnp no)
		(fields_autoplaced yes)
		(property "Reference" "N1"
			(at 104.14 274.8762 0)
			(effects
				(font
					(size 1.27 1.27)
				)
				(justify left)
			)
		)
		(property "Value" "antmicro_logo"
			(at 104.14 277.4162 0)
			(effects
				(font
					(size 1.27 1.27)
				)
				(justify left)
			)
		)
		(property "Footprint" "antmicro-footprints:antmicro-logo"
			(at 95.25 270.51 0)
			(effects
				(font
					(size 1.27 1.27)
				)
				(hide yes)
			)
		)
		(property "Datasheet" ""
			(at 97.79 267.97 0)
			(effects
				(font
					(size 1.27 1.27)
				)
				(hide yes)
			)
		)
		(property "Description" "Mechanical part"
			(at 97.79 276.86 0)
			(effects
				(font
					(size 1.27 1.27)
				)
				(hide yes)
			)
		)
		(property "MPN" ""
			(at 97.79 276.86 0)
			(effects
				(font
					(size 1.27 1.27)
				)
				(hide yes)
			)
		)
		(property "Manufacturer" ""
			(at 113.03 297.18 0)
			(effects
				(font
					(size 1.27 1.27)
					(thickness 0.15)
				)
				(justify left bottom)
				(hide yes)
			)
		)
		(property "Author" "Antmicro"
			(at 113.03 292.1 0)
			(effects
				(font
					(size 1.27 1.27)
					(thickness 0.15)
				)
				(justify left bottom)
				(hide yes)
			)
		)
		(property "License" "Apache-2.0"
			(at 113.03 294.64 0)
			(effects
				(font
					(size 1.27 1.27)
					(thickness 0.15)
				)
				(justify left bottom)
				(hide yes)
			)
		)
		(property "Public" "False"
			(at 113.03 297.18 0)
			(effects
				(font
					(size 1.27 1.27)
				)
				(justify left bottom)
				(hide yes)
			)
		)
		(instances
			(project "m2-pcie-adapter"
				(path ""
					(reference "N1")
					(unit 1)
				)
			)
		)
	)
	(symbol
		(lib_id "antmicroMechanicalParts:oshw_logo")
		(at 97.79 267.97 0)
		(unit 1)
		(exclude_from_sim no)
		(in_bom yes)
		(on_board yes)
		(dnp no)
		(fields_autoplaced yes)
		(property "Reference" "N2"
			(at 104.14 265.9862 0)
			(effects
				(font
					(size 1.27 1.27)
				)
				(justify left)
			)
		)
		(property "Value" "oshw_logo"
			(at 104.14 268.5262 0)
			(effects
				(font
					(size 1.27 1.27)
				)
				(justify left)
			)
		)
		(property "Footprint" "antmicro-footprints:oshw-logo"
			(at 98.298 274.066 0)
			(effects
				(font
					(size 1.27 1.27)
				)
				(hide yes)
			)
		)
		(property "Datasheet" ""
			(at 97.79 267.97 0)
			(effects
				(font
					(size 1.27 1.27)
				)
				(hide yes)
			)
		)
		(property "Description" "Mechanical part"
			(at 97.79 267.97 0)
			(effects
				(font
					(size 1.27 1.27)
				)
				(hide yes)
			)
		)
		(property "Author" "Antmicro"
			(at 113.03 283.21 0)
			(effects
				(font
					(size 1.27 1.27)
					(thickness 0.15)
				)
				(justify left bottom)
				(hide yes)
			)
		)
		(property "License" "Apache-2.0"
			(at 113.03 285.75 0)
			(effects
				(font
					(size 1.27 1.27)
					(thickness 0.15)
				)
				(justify left bottom)
				(hide yes)
			)
		)
		(property "MPN" ""
			(at 97.79 267.97 0)
			(effects
				(font
					(size 1.27 1.27)
				)
				(hide yes)
			)
		)
		(property "Manufacturer" ""
			(at 113.03 288.29 0)
			(effects
				(font
					(size 1.27 1.27)
					(thickness 0.15)
				)
				(justify left bottom)
				(hide yes)
			)
		)
		(property "Public" "False"
			(at 113.03 288.29 0)
			(effects
				(font
					(size 1.27 1.27)
				)
				(justify left bottom)
				(hide yes)
			)
		)
		(instances
			(project "m2-pcie-adapter"
				(path ""
					(reference "N2")
					(unit 1)
				)
			)
		)
	)
	(symbol
		(lib_id "antmicropower:GND")
		(at 50.8 213.36 0)
		(unit 1)
		(exclude_from_sim no)
		(in_bom yes)
		(on_board yes)
		(dnp no)
		(property "Reference" "#PWR01"
			(at 50.8 219.71 0)
			(effects
				(font
					(size 1.27 1.27)
				)
				(hide yes)
			)
		)
		(property "Value" "GND"
			(at 50.927 217.7542 0)
			(effects
				(font
					(size 1.27 1.27)
				)
			)
		)
		(property "Footprint" ""
			(at 50.8 213.36 0)
			(effects
				(font
					(size 1.27 1.27)
				)
				(hide yes)
			)
		)
		(property "Datasheet" ""
			(at 50.8 213.36 0)
			(effects
				(font
					(size 1.27 1.27)
				)
				(hide yes)
			)
		)
		(property "Description" ""
			(at 50.8 213.36 0)
			(effects
				(font
					(size 1.27 1.27)
				)
				(hide yes)
			)
		)
		(property "Author" "Antmicro"
			(at 59.69 220.98 0)
			(effects
				(font
					(size 1.27 1.27)
					(thickness 0.15)
				)
				(justify left bottom)
				(hide yes)
			)
		)
		(property "License" "Apache-2.0"
			(at 59.69 223.52 0)
			(effects
				(font
					(size 1.27 1.27)
					(thickness 0.15)
				)
				(justify left bottom)
				(hide yes)
			)
		)
		(pin "1"
		)
		(instances
			(project "m2-pcie-adapter"
				(path ""
					(reference "#PWR01")
					(unit 1)
				)
			)
		)
	)
	(sheet_instances
		(path "/"
			(page "1")
		)
	)
)
